(kicad_sch
	(version 20250114)
	(generator "eeschema")
	(generator_version "9.0")
	(paper "A3")
	(title_block
		(title "LPDDR5 Testbed")
		(date "2023-12-19")
		(rev "1.0.0")
	)
	(text " 0.5V NOM"
		(exclude_from_sim no)
		(at 168.275 66.675 0)
		(effects
			(font
				(size 1.27 1.27)
			)
			(justify left bottom)
		)
	)
	(text " 0.9V NOM"
		(exclude_from_sim no)
		(at 215.265 66.675 0)
		(effects
			(font
				(size 1.27 1.27)
			)
			(justify left bottom)
		)
	)
	(text " 1.05V NOM"
		(exclude_from_sim no)
		(at 215.265 33.655 0)
		(effects
			(font
				(size 1.27 1.27)
			)
			(justify left bottom)
		)
	)
	(text "LPDDR5\n"
		(exclude_from_sim no)
		(at 27.305 26.035 0)
		(effects
			(font
				(size 2.4892 2.4892)
				(thickness 0.4978)
				(bold yes)
			)
			(justify left bottom)
		)
	)
	(text " 1.8V NOM"
		(exclude_from_sim no)
		(at 168.275 59.055 0)
		(effects
			(font
				(size 1.27 1.27)
			)
			(justify left bottom)
		)
	)
	(junction
		(at 213.36 129.54)
		(diameter 0)
		(color 0 0 0 0)
	)
	(junction
		(at 140.97 67.31)
		(diameter 0)
		(color 0 0 0 0)
	)
	(junction
		(at 229.87 48.26)
		(diameter 0)
		(color 0 0 0 0)
	)
	(junction
		(at 215.9 67.31)
		(diameter 0)
		(color 0 0 0 0)
	)
	(junction
		(at 123.19 67.31)
		(diameter 0)
		(color 0 0 0 0)
	)
	(junction
		(at 247.65 34.29)
		(diameter 0)
		(color 0 0 0 0)
	)
	(junction
		(at 157.48 67.31)
		(diameter 0)
		(color 0 0 0 0)
	)
	(junction
		(at 229.87 34.29)
		(diameter 0)
		(color 0 0 0 0)
	)
	(junction
		(at 80.01 129.54)
		(diameter 0)
		(color 0 0 0 0)
	)
	(junction
		(at 283.21 34.29)
		(diameter 0)
		(color 0 0 0 0)
	)
	(junction
		(at 229.87 81.28)
		(diameter 0)
		(color 0 0 0 0)
	)
	(junction
		(at 132.08 67.31)
		(diameter 0)
		(color 0 0 0 0)
	)
	(junction
		(at 222.25 34.29)
		(diameter 0)
		(color 0 0 0 0)
	)
	(junction
		(at 149.86 67.31)
		(diameter 0)
		(color 0 0 0 0)
	)
	(junction
		(at 265.43 48.26)
		(diameter 0)
		(color 0 0 0 0)
	)
	(junction
		(at 105.41 67.31)
		(diameter 0)
		(color 0 0 0 0)
	)
	(junction
		(at 256.54 67.31)
		(diameter 0)
		(color 0 0 0 0)
	)
	(junction
		(at 256.54 48.26)
		(diameter 0)
		(color 0 0 0 0)
	)
	(junction
		(at 238.76 34.29)
		(diameter 0)
		(color 0 0 0 0)
	)
	(junction
		(at 247.65 81.28)
		(diameter 0)
		(color 0 0 0 0)
	)
	(junction
		(at 132.08 50.8)
		(diameter 0)
		(color 0 0 0 0)
	)
	(junction
		(at 140.97 50.8)
		(diameter 0)
		(color 0 0 0 0)
	)
	(junction
		(at 274.32 34.29)
		(diameter 0)
		(color 0 0 0 0)
	)
	(junction
		(at 114.3 81.28)
		(diameter 0)
		(color 0 0 0 0)
	)
	(junction
		(at 265.43 34.29)
		(diameter 0)
		(color 0 0 0 0)
	)
	(junction
		(at 247.65 67.31)
		(diameter 0)
		(color 0 0 0 0)
	)
	(junction
		(at 123.19 50.8)
		(diameter 0)
		(color 0 0 0 0)
	)
	(junction
		(at 247.65 48.26)
		(diameter 0)
		(color 0 0 0 0)
	)
	(junction
		(at 114.3 67.31)
		(diameter 0)
		(color 0 0 0 0)
	)
	(junction
		(at 149.86 81.28)
		(diameter 0)
		(color 0 0 0 0)
	)
	(junction
		(at 238.76 67.31)
		(diameter 0)
		(color 0 0 0 0)
	)
	(junction
		(at 132.08 81.28)
		(diameter 0)
		(color 0 0 0 0)
	)
	(junction
		(at 238.76 48.26)
		(diameter 0)
		(color 0 0 0 0)
	)
	(junction
		(at 140.97 81.28)
		(diameter 0)
		(color 0 0 0 0)
	)
	(junction
		(at 229.87 67.31)
		(diameter 0)
		(color 0 0 0 0)
	)
	(junction
		(at 238.76 81.28)
		(diameter 0)
		(color 0 0 0 0)
	)
	(junction
		(at 123.19 81.28)
		(diameter 0)
		(color 0 0 0 0)
	)
	(junction
		(at 149.86 50.8)
		(diameter 0)
		(color 0 0 0 0)
	)
	(junction
		(at 274.32 48.26)
		(diameter 0)
		(color 0 0 0 0)
	)
	(junction
		(at 256.54 34.29)
		(diameter 0)
		(color 0 0 0 0)
	)
	(bus_entry
		(at 160.02 191.77)
		(size -1.27 1.27)
		(stroke
			(width 0)
			(type default)
		)
	)
	(bus_entry
		(at 80.01 189.23)
		(size 1.27 1.27)
		(stroke
			(width 0)
			(type default)
		)
	)
	(bus_entry
		(at 160.02 156.21)
		(size -1.27 1.27)
		(stroke
			(width 0)
			(type default)
		)
	)
	(bus_entry
		(at 160.02 148.59)
		(size -1.27 1.27)
		(stroke
			(width 0)
			(type default)
		)
	)
	(bus_entry
		(at 80.01 184.15)
		(size 1.27 1.27)
		(stroke
			(width 0)
			(type default)
		)
	)
	(bus_entry
		(at 160.02 161.29)
		(size -1.27 1.27)
		(stroke
			(width 0)
			(type default)
		)
	)
	(bus_entry
		(at 160.02 151.13)
		(size -1.27 1.27)
		(stroke
			(width 0)
			(type default)
		)
	)
	(bus_entry
		(at 293.37 143.51)
		(size -1.27 1.27)
		(stroke
			(width 0)
			(type default)
		)
	)
	(bus_entry
		(at 213.36 143.51)
		(size 1.27 1.27)
		(stroke
			(width 0)
			(type default)
		)
	)
	(bus_entry
		(at 293.37 179.07)
		(size -1.27 1.27)
		(stroke
			(width 0)
			(type default)
		)
	)
	(bus_entry
		(at 213.36 156.21)
		(size 1.27 1.27)
		(stroke
			(width 0)
			(type default)
		)
	)
	(bus_entry
		(at 213.36 194.31)
		(size 1.27 1.27)
		(stroke
			(width 0)
			(type default)
		)
	)
	(bus_entry
		(at 160.02 168.91)
		(size -1.27 1.27)
		(stroke
			(width 0)
			(type default)
		)
	)
	(bus_entry
		(at 213.36 184.15)
		(size 1.27 1.27)
		(stroke
			(width 0)
			(type default)
		)
	)
	(bus_entry
		(at 213.36 173.99)
		(size 1.27 1.27)
		(stroke
			(width 0)
			(type default)
		)
	)
	(bus_entry
		(at 160.02 173.99)
		(size -1.27 1.27)
		(stroke
			(width 0)
			(type default)
		)
	)
	(bus_entry
		(at 80.01 191.77)
		(size 1.27 1.27)
		(stroke
			(width 0)
			(type default)
		)
	)
	(bus_entry
		(at 293.37 148.59)
		(size -1.27 1.27)
		(stroke
			(width 0)
			(type default)
		)
	)
	(bus_entry
		(at 160.02 194.31)
		(size -1.27 1.27)
		(stroke
			(width 0)
			(type default)
		)
	)
	(bus_entry
		(at 160.02 189.23)
		(size -1.27 1.27)
		(stroke
			(width 0)
			(type default)
		)
	)
	(bus_entry
		(at 80.01 181.61)
		(size 1.27 1.27)
		(stroke
			(width 0)
			(type default)
		)
	)
	(bus_entry
		(at 80.01 179.07)
		(size 1.27 1.27)
		(stroke
			(width 0)
			(type default)
		)
	)
	(bus_entry
		(at 80.01 186.69)
		(size 1.27 1.27)
		(stroke
			(width 0)
			(type default)
		)
	)
	(bus_entry
		(at 293.37 189.23)
		(size -1.27 1.27)
		(stroke
			(width 0)
			(type default)
		)
	)
	(bus_entry
		(at 213.36 151.13)
		(size 1.27 1.27)
		(stroke
			(width 0)
			(type default)
		)
	)
	(bus_entry
		(at 293.37 171.45)
		(size -1.27 1.27)
		(stroke
			(width 0)
			(type default)
		)
	)
	(bus_entry
		(at 293.37 163.83)
		(size -1.27 1.27)
		(stroke
			(width 0)
			(type default)
		)
	)
	(bus_entry
		(at 160.02 171.45)
		(size -1.27 1.27)
		(stroke
			(width 0)
			(type default)
		)
	)
	(bus_entry
		(at 293.37 166.37)
		(size -1.27 1.27)
		(stroke
			(width 0)
			(type default)
		)
	)
	(bus_entry
		(at 293.37 156.21)
		(size -1.27 1.27)
		(stroke
			(width 0)
			(type default)
		)
	)
	(bus_entry
		(at 293.37 194.31)
		(size -1.27 1.27)
		(stroke
			(width 0)
			(type default)
		)
	)
	(bus_entry
		(at 293.37 173.99)
		(size -1.27 1.27)
		(stroke
			(width 0)
			(type default)
		)
	)
	(bus_entry
		(at 293.37 186.69)
		(size -1.27 1.27)
		(stroke
			(width 0)
			(type default)
		)
	)
	(bus_entry
		(at 80.01 143.51)
		(size 1.27 1.27)
		(stroke
			(width 0)
			(type default)
		)
	)
	(bus_entry
		(at 293.37 140.97)
		(size -1.27 1.27)
		(stroke
			(width 0)
			(type default)
		)
	)
	(bus_entry
		(at 293.37 151.13)
		(size -1.27 1.27)
		(stroke
			(width 0)
			(type default)
		)
	)
	(bus_entry
		(at 293.37 158.75)
		(size -1.27 1.27)
		(stroke
			(width 0)
			(type default)
		)
	)
	(bus_entry
		(at 80.01 156.21)
		(size 1.27 1.27)
		(stroke
			(width 0)
			(type default)
		)
	)
	(bus_entry
		(at 80.01 194.31)
		(size 1.27 1.27)
		(stroke
			(width 0)
			(type default)
		)
	)
	(bus_entry
		(at 213.36 171.45)
		(size 1.27 1.27)
		(stroke
			(width 0)
			(type default)
		)
	)
	(bus_entry
		(at 160.02 186.69)
		(size -1.27 1.27)
		(stroke
			(width 0)
			(type default)
		)
	)
	(bus_entry
		(at 293.37 191.77)
		(size -1.27 1.27)
		(stroke
			(width 0)
			(type default)
		)
	)
	(bus_entry
		(at 80.01 158.75)
		(size 1.27 1.27)
		(stroke
			(width 0)
			(type default)
		)
	)
	(bus_entry
		(at 80.01 140.97)
		(size 1.27 1.27)
		(stroke
			(width 0)
			(type default)
		)
	)
	(bus_entry
		(at 213.36 148.59)
		(size 1.27 1.27)
		(stroke
			(width 0)
			(type default)
		)
	)
	(bus_entry
		(at 80.01 166.37)
		(size 1.27 1.27)
		(stroke
			(width 0)
			(type default)
		)
	)
	(bus_entry
		(at 293.37 184.15)
		(size -1.27 1.27)
		(stroke
			(width 0)
			(type default)
		)
	)
	(bus_entry
		(at 80.01 148.59)
		(size 1.27 1.27)
		(stroke
			(width 0)
			(type default)
		)
	)
	(bus_entry
		(at 160.02 184.15)
		(size -1.27 1.27)
		(stroke
			(width 0)
			(type default)
		)
	)
	(bus_entry
		(at 160.02 158.75)
		(size -1.27 1.27)
		(stroke
			(width 0)
			(type default)
		)
	)
	(bus_entry
		(at 293.37 161.29)
		(size -1.27 1.27)
		(stroke
			(width 0)
			(type default)
		)
	)
	(bus_entry
		(at 213.36 166.37)
		(size 1.27 1.27)
		(stroke
			(width 0)
			(type default)
		)
	)
	(bus_entry
		(at 80.01 151.13)
		(size 1.27 1.27)
		(stroke
			(width 0)
			(type default)
		)
	)
	(bus_entry
		(at 80.01 163.83)
		(size 1.27 1.27)
		(stroke
			(width 0)
			(type default)
		)
	)
	(bus_entry
		(at 293.37 181.61)
		(size -1.27 1.27)
		(stroke
			(width 0)
			(type default)
		)
	)
	(bus_entry
		(at 160.02 143.51)
		(size -1.27 1.27)
		(stroke
			(width 0)
			(type default)
		)
	)
	(bus_entry
		(at 293.37 176.53)
		(size -1.27 1.27)
		(stroke
			(width 0)
			(type default)
		)
	)
	(bus_entry
		(at 80.01 173.99)
		(size 1.27 1.27)
		(stroke
			(width 0)
			(type default)
		)
	)
	(bus_entry
		(at 213.36 158.75)
		(size 1.27 1.27)
		(stroke
			(width 0)
			(type default)
		)
	)
	(bus_entry
		(at 213.36 186.69)
		(size 1.27 1.27)
		(stroke
			(width 0)
			(type default)
		)
	)
	(bus_entry
		(at 160.02 181.61)
		(size -1.27 1.27)
		(stroke
			(width 0)
			(type default)
		)
	)
	(bus_entry
		(at 80.01 171.45)
		(size 1.27 1.27)
		(stroke
			(width 0)
			(type default)
		)
	)
	(bus_entry
		(at 213.36 189.23)
		(size 1.27 1.27)
		(stroke
			(width 0)
			(type default)
		)
	)
	(bus_entry
		(at 160.02 140.97)
		(size -1.27 1.27)
		(stroke
			(width 0)
			(type default)
		)
	)
	(bus_entry
		(at 160.02 176.53)
		(size -1.27 1.27)
		(stroke
			(width 0)
			(type default)
		)
	)
	(bus_entry
		(at 160.02 163.83)
		(size -1.27 1.27)
		(stroke
			(width 0)
			(type default)
		)
	)
	(bus_entry
		(at 213.36 181.61)
		(size 1.27 1.27)
		(stroke
			(width 0)
			(type default)
		)
	)
	(bus_entry
		(at 160.02 166.37)
		(size -1.27 1.27)
		(stroke
			(width 0)
			(type default)
		)
	)
	(bus_entry
		(at 213.36 191.77)
		(size 1.27 1.27)
		(stroke
			(width 0)
			(type default)
		)
	)
	(bus_entry
		(at 213.36 140.97)
		(size 1.27 1.27)
		(stroke
			(width 0)
			(type default)
		)
	)
	(bus_entry
		(at 213.36 163.83)
		(size 1.27 1.27)
		(stroke
			(width 0)
			(type default)
		)
	)
	(bus_entry
		(at 293.37 168.91)
		(size -1.27 1.27)
		(stroke
			(width 0)
			(type default)
		)
	)
	(bus_entry
		(at 213.36 179.07)
		(size 1.27 1.27)
		(stroke
			(width 0)
			(type default)
		)
	)
	(bus_entry
		(at 160.02 179.07)
		(size -1.27 1.27)
		(stroke
			(width 0)
			(type default)
		)
	)
	(wire
		(pts
			(xy 270.51 149.86) (xy 292.1 149.86)
		)
		(stroke
			(width 0)
			(type default)
		)
	)
	(wire
		(pts
			(xy 157.48 81.28) (xy 157.48 67.31)
		)
		(stroke
			(width 0)
			(type default)
		)
	)
	(wire
		(pts
			(xy 270.51 187.96) (xy 292.1 187.96)
		)
		(stroke
			(width 0)
			(type default)
		)
	)
	(wire
		(pts
			(xy 215.9 34.29) (xy 215.9 59.69)
		)
		(stroke
			(width 0)
			(type default)
		)
	)
	(wire
		(pts
			(xy 256.54 34.29) (xy 247.65 34.29)
		)
		(stroke
			(width 0)
			(type default)
		)
	)
	(wire
		(pts
			(xy 283.21 34.29) (xy 283.21 35.56)
		)
		(stroke
			(width 0)
			(type default)
		)
	)
	(wire
		(pts
			(xy 247.65 48.26) (xy 247.65 49.53)
		)
		(stroke
			(width 0)
			(type default)
		)
	)
	(bus
		(pts
			(xy 293.37 130.81) (xy 292.1 129.54)
		)
		(stroke
			(width 0)
			(type default)
		)
	)
	(wire
		(pts
			(xy 270.51 175.26) (xy 292.1 175.26)
		)
		(stroke
			(width 0)
			(type default)
		)
	)
	(wire
		(pts
			(xy 238.76 81.28) (xy 247.65 81.28)
		)
		(stroke
			(width 0)
			(type default)
		)
	)
	(bus
		(pts
			(xy 213.36 179.07) (xy 213.36 181.61)
		)
		(stroke
			(width 0)
			(type default)
		)
	)
	(bus
		(pts
			(xy 160.02 166.37) (xy 160.02 168.91)
		)
		(stroke
			(width 0)
			(type default)
		)
	)
	(wire
		(pts
			(xy 214.63 149.86) (xy 236.22 149.86)
		)
		(stroke
			(width 0)
			(type default)
		)
	)
	(wire
		(pts
			(xy 123.19 50.8) (xy 119.38 50.8)
		)
		(stroke
			(width 0)
			(type default)
		)
	)
	(wire
		(pts
			(xy 137.16 193.04) (xy 158.75 193.04)
		)
		(stroke
			(width 0)
			(type default)
		)
	)
	(wire
		(pts
			(xy 137.16 185.42) (xy 158.75 185.42)
		)
		(stroke
			(width 0)
			(type default)
		)
	)
	(bus
		(pts
			(xy 213.36 171.45) (xy 213.36 173.99)
		)
		(stroke
			(width 0)
			(type default)
		)
	)
	(wire
		(pts
			(xy 105.41 67.31) (xy 114.3 67.31)
		)
		(stroke
			(width 0)
			(type default)
		)
	)
	(wire
		(pts
			(xy 81.28 167.64) (xy 102.87 167.64)
		)
		(stroke
			(width 0)
			(type default)
		)
	)
	(wire
		(pts
			(xy 137.16 187.96) (xy 158.75 187.96)
		)
		(stroke
			(width 0)
			(type default)
		)
	)
	(wire
		(pts
			(xy 81.28 190.5) (xy 102.87 190.5)
		)
		(stroke
			(width 0)
			(type default)
		)
	)
	(wire
		(pts
			(xy 256.54 48.26) (xy 247.65 48.26)
		)
		(stroke
			(width 0)
			(type default)
		)
	)
	(wire
		(pts
			(xy 214.63 167.64) (xy 236.22 167.64)
		)
		(stroke
			(width 0)
			(type default)
		)
	)
	(wire
		(pts
			(xy 274.32 34.29) (xy 283.21 34.29)
		)
		(stroke
			(width 0)
			(type default)
		)
	)
	(bus
		(pts
			(xy 293.37 130.81) (xy 293.37 140.97)
		)
		(stroke
			(width 0)
			(type default)
		)
	)
	(wire
		(pts
			(xy 214.63 195.58) (xy 236.22 195.58)
		)
		(stroke
			(width 0)
			(type default)
		)
	)
	(wire
		(pts
			(xy 137.16 160.02) (xy 158.75 160.02)
		)
		(stroke
			(width 0)
			(type default)
		)
	)
	(wire
		(pts
			(xy 270.51 182.88) (xy 292.1 182.88)
		)
		(stroke
			(width 0)
			(type default)
		)
	)
	(wire
		(pts
			(xy 137.16 177.8) (xy 158.75 177.8)
		)
		(stroke
			(width 0)
			(type default)
		)
	)
	(wire
		(pts
			(xy 256.54 48.26) (xy 256.54 49.53)
		)
		(stroke
			(width 0)
			(type default)
		)
	)
	(wire
		(pts
			(xy 149.86 50.8) (xy 149.86 52.07)
		)
		(stroke
			(width 0)
			(type default)
		)
	)
	(wire
		(pts
			(xy 214.63 182.88) (xy 236.22 182.88)
		)
		(stroke
			(width 0)
			(type default)
		)
	)
	(bus
		(pts
			(xy 293.37 179.07) (xy 293.37 181.61)
		)
		(stroke
			(width 0)
			(type default)
		)
	)
	(wire
		(pts
			(xy 170.18 82.55) (xy 170.18 83.82)
		)
		(stroke
			(width 0)
			(type default)
		)
	)
	(bus
		(pts
			(xy 293.37 161.29) (xy 293.37 163.83)
		)
		(stroke
			(width 0)
			(type default)
		)
	)
	(wire
		(pts
			(xy 81.28 157.48) (xy 102.87 157.48)
		)
		(stroke
			(width 0)
			(type default)
		)
	)
	(wire
		(pts
			(xy 238.76 48.26) (xy 238.76 49.53)
		)
		(stroke
			(width 0)
			(type default)
		)
	)
	(wire
		(pts
			(xy 229.87 67.31) (xy 238.76 67.31)
		)
		(stroke
			(width 0)
			(type default)
		)
	)
	(wire
		(pts
			(xy 215.9 81.28) (xy 229.87 81.28)
		)
		(stroke
			(width 0)
			(type default)
		)
	)
	(wire
		(pts
			(xy 81.28 182.88) (xy 102.87 182.88)
		)
		(stroke
			(width 0)
			(type default)
		)
	)
	(bus
		(pts
			(xy 160.02 171.45) (xy 160.02 173.99)
		)
		(stroke
			(width 0)
			(type default)
		)
	)
	(wire
		(pts
			(xy 123.19 50.8) (xy 132.08 50.8)
		)
		(stroke
			(width 0)
			(type default)
		)
	)
	(wire
		(pts
			(xy 132.08 50.8) (xy 140.97 50.8)
		)
		(stroke
			(width 0)
			(type default)
		)
	)
	(bus
		(pts
			(xy 293.37 143.51) (xy 293.37 148.59)
		)
		(stroke
			(width 0)
			(type default)
		)
	)
	(wire
		(pts
			(xy 270.51 160.02) (xy 292.1 160.02)
		)
		(stroke
			(width 0)
			(type default)
		)
	)
	(wire
		(pts
			(xy 123.19 81.28) (xy 132.08 81.28)
		)
		(stroke
			(width 0)
			(type default)
		)
	)
	(wire
		(pts
			(xy 238.76 34.29) (xy 229.87 34.29)
		)
		(stroke
			(width 0)
			(type default)
		)
	)
	(wire
		(pts
			(xy 247.65 81.28) (xy 256.54 81.28)
		)
		(stroke
			(width 0)
			(type default)
		)
	)
	(wire
		(pts
			(xy 81.28 175.26) (xy 102.87 175.26)
		)
		(stroke
			(width 0)
			(type default)
		)
	)
	(wire
		(pts
			(xy 140.97 67.31) (xy 140.97 68.58)
		)
		(stroke
			(width 0)
			(type default)
		)
	)
	(wire
		(pts
			(xy 270.51 190.5) (xy 292.1 190.5)
		)
		(stroke
			(width 0)
			(type default)
		)
	)
	(wire
		(pts
			(xy 265.43 34.29) (xy 274.32 34.29)
		)
		(stroke
			(width 0)
			(type default)
		)
	)
	(bus
		(pts
			(xy 213.36 189.23) (xy 213.36 191.77)
		)
		(stroke
			(width 0)
			(type default)
		)
	)
	(bus
		(pts
			(xy 80.01 158.75) (xy 80.01 163.83)
		)
		(stroke
			(width 0)
			(type default)
		)
	)
	(bus
		(pts
			(xy 160.02 163.83) (xy 160.02 166.37)
		)
		(stroke
			(width 0)
			(type default)
		)
	)
	(wire
		(pts
			(xy 123.19 67.31) (xy 123.19 68.58)
		)
		(stroke
			(width 0)
			(type default)
		)
	)
	(bus
		(pts
			(xy 213.36 163.83) (xy 213.36 166.37)
		)
		(stroke
			(width 0)
			(type default)
		)
	)
	(bus
		(pts
			(xy 293.37 173.99) (xy 293.37 176.53)
		)
		(stroke
			(width 0)
			(type default)
		)
	)
	(wire
		(pts
			(xy 132.08 67.31) (xy 140.97 67.31)
		)
		(stroke
			(width 0)
			(type default)
		)
	)
	(wire
		(pts
			(xy 170.18 74.93) (xy 170.18 77.47)
		)
		(stroke
			(width 0)
			(type default)
		)
	)
	(wire
		(pts
			(xy 270.51 185.42) (xy 292.1 185.42)
		)
		(stroke
			(width 0)
			(type default)
		)
	)
	(bus
		(pts
			(xy 160.02 181.61) (xy 160.02 184.15)
		)
		(stroke
			(width 0)
			(type default)
		)
	)
	(bus
		(pts
			(xy 80.01 171.45) (xy 80.01 173.99)
		)
		(stroke
			(width 0)
			(type default)
		)
	)
	(wire
		(pts
			(xy 287.02 33.02) (xy 287.02 34.29)
		)
		(stroke
			(width 0)
			(type default)
		)
	)
	(wire
		(pts
			(xy 215.9 59.69) (xy 213.36 59.69)
		)
		(stroke
			(width 0)
			(type default)
		)
	)
	(bus
		(pts
			(xy 293.37 171.45) (xy 293.37 173.99)
		)
		(stroke
			(width 0)
			(type default)
		)
	)
	(wire
		(pts
			(xy 123.19 81.28) (xy 123.19 82.55)
		)
		(stroke
			(width 0)
			(type default)
		)
	)
	(wire
		(pts
			(xy 137.16 172.72) (xy 158.75 172.72)
		)
		(stroke
			(width 0)
			(type default)
		)
	)
	(wire
		(pts
			(xy 270.51 177.8) (xy 292.1 177.8)
		)
		(stroke
			(width 0)
			(type default)
		)
	)
	(wire
		(pts
			(xy 238.76 67.31) (xy 247.65 67.31)
		)
		(stroke
			(width 0)
			(type default)
		)
	)
	(bus
		(pts
			(xy 80.01 151.13) (xy 80.01 156.21)
		)
		(stroke
			(width 0)
			(type default)
		)
	)
	(bus
		(pts
			(xy 80.01 191.77) (xy 80.01 194.31)
		)
		(stroke
			(width 0)
			(type default)
		)
	)
	(wire
		(pts
			(xy 100.33 67.31) (xy 105.41 67.31)
		)
		(stroke
			(width 0)
			(type default)
		)
	)
	(bus
		(pts
			(xy 160.02 140.97) (xy 160.02 143.51)
		)
		(stroke
			(width 0)
			(type default)
		)
	)
	(bus
		(pts
			(xy 213.36 173.99) (xy 213.36 179.07)
		)
		(stroke
			(width 0)
			(type default)
		)
	)
	(wire
		(pts
			(xy 81.28 152.4) (xy 102.87 152.4)
		)
		(stroke
			(width 0)
			(type default)
		)
	)
	(wire
		(pts
			(xy 149.86 50.8) (xy 157.48 50.8)
		)
		(stroke
			(width 0)
			(type default)
		)
	)
	(bus
		(pts
			(xy 160.02 158.75) (xy 160.02 161.29)
		)
		(stroke
			(width 0)
			(type default)
		)
	)
	(bus
		(pts
			(xy 160.02 161.29) (xy 160.02 163.83)
		)
		(stroke
			(width 0)
			(type default)
		)
	)
	(wire
		(pts
			(xy 149.86 67.31) (xy 149.86 68.58)
		)
		(stroke
			(width 0)
			(type default)
		)
	)
	(wire
		(pts
			(xy 270.51 144.78) (xy 292.1 144.78)
		)
		(stroke
			(width 0)
			(type default)
		)
	)
	(wire
		(pts
			(xy 214.63 152.4) (xy 236.22 152.4)
		)
		(stroke
			(width 0)
			(type default)
		)
	)
	(bus
		(pts
			(xy 213.36 143.51) (xy 213.36 148.59)
		)
		(stroke
			(width 0)
			(type default)
		)
	)
	(wire
		(pts
			(xy 179.07 82.55) (xy 177.8 82.55)
		)
		(stroke
			(width 0)
			(type default)
		)
	)
	(wire
		(pts
			(xy 222.25 48.26) (xy 222.25 34.29)
		)
		(stroke
			(width 0)
			(type default)
		)
	)
	(wire
		(pts
			(xy 214.63 180.34) (xy 236.22 180.34)
		)
		(stroke
			(width 0)
			(type default)
		)
	)
	(bus
		(pts
			(xy 160.02 151.13) (xy 160.02 156.21)
		)
		(stroke
			(width 0)
			(type default)
		)
	)
	(bus
		(pts
			(xy 213.36 140.97) (xy 213.36 143.51)
		)
		(stroke
			(width 0)
			(type default)
		)
	)
	(wire
		(pts
			(xy 157.48 67.31) (xy 179.07 67.31)
		)
		(stroke
			(width 0)
			(type default)
		)
	)
	(wire
		(pts
			(xy 140.97 50.8) (xy 149.86 50.8)
		)
		(stroke
			(width 0)
			(type default)
		)
	)
	(bus
		(pts
			(xy 213.36 158.75) (xy 213.36 163.83)
		)
		(stroke
			(width 0)
			(type default)
		)
	)
	(bus
		(pts
			(xy 160.02 191.77) (xy 160.02 194.31)
		)
		(stroke
			(width 0)
			(type default)
		)
	)
	(bus
		(pts
			(xy 160.02 189.23) (xy 160.02 191.77)
		)
		(stroke
			(width 0)
			(type default)
		)
	)
	(wire
		(pts
			(xy 100.33 66.04) (xy 100.33 67.31)
		)
		(stroke
			(width 0)
			(type default)
		)
	)
	(bus
		(pts
			(xy 160.02 186.69) (xy 160.02 189.23)
		)
		(stroke
			(width 0)
			(type default)
		)
	)
	(wire
		(pts
			(xy 149.86 81.28) (xy 157.48 81.28)
		)
		(stroke
			(width 0)
			(type default)
		)
	)
	(wire
		(pts
			(xy 238.76 67.31) (xy 238.76 68.58)
		)
		(stroke
			(width 0)
			(type default)
		)
	)
	(wire
		(pts
			(xy 215.9 81.28) (xy 215.9 67.31)
		)
		(stroke
			(width 0)
			(type default)
		)
	)
	(wire
		(pts
			(xy 247.65 34.29) (xy 238.76 34.29)
		)
		(stroke
			(width 0)
			(type default)
		)
	)
	(bus
		(pts
			(xy 80.01 166.37) (xy 80.01 171.45)
		)
		(stroke
			(width 0)
			(type default)
		)
	)
	(wire
		(pts
			(xy 137.16 167.64) (xy 158.75 167.64)
		)
		(stroke
			(width 0)
			(type default)
		)
	)
	(bus
		(pts
			(xy 293.37 166.37) (xy 293.37 168.91)
		)
		(stroke
			(width 0)
			(type default)
		)
	)
	(wire
		(pts
			(xy 137.16 165.1) (xy 158.75 165.1)
		)
		(stroke
			(width 0)
			(type default)
		)
	)
	(wire
		(pts
			(xy 238.76 48.26) (xy 229.87 48.26)
		)
		(stroke
			(width 0)
			(type default)
		)
	)
	(wire
		(pts
			(xy 247.65 34.29) (xy 247.65 35.56)
		)
		(stroke
			(width 0)
			(type default)
		)
	)
	(bus
		(pts
			(xy 293.37 151.13) (xy 293.37 156.21)
		)
		(stroke
			(width 0)
			(type default)
		)
	)
	(bus
		(pts
			(xy 160.02 168.91) (xy 160.02 171.45)
		)
		(stroke
			(width 0)
			(type default)
		)
	)
	(wire
		(pts
			(xy 229.87 67.31) (xy 229.87 68.58)
		)
		(stroke
			(width 0)
			(type default)
		)
	)
	(wire
		(pts
			(xy 81.28 144.78) (xy 102.87 144.78)
		)
		(stroke
			(width 0)
			(type default)
		)
	)
	(wire
		(pts
			(xy 114.3 67.31) (xy 114.3 68.58)
		)
		(stroke
			(width 0)
			(type default)
		)
	)
	(wire
		(pts
			(xy 149.86 67.31) (xy 157.48 67.31)
		)
		(stroke
			(width 0)
			(type default)
		)
	)
	(wire
		(pts
			(xy 137.16 175.26) (xy 158.75 175.26)
		)
		(stroke
			(width 0)
			(type default)
		)
	)
	(wire
		(pts
			(xy 81.28 149.86) (xy 102.87 149.86)
		)
		(stroke
			(width 0)
			(type default)
		)
	)
	(wire
		(pts
			(xy 270.51 180.34) (xy 292.1 180.34)
		)
		(stroke
			(width 0)
			(type default)
		)
	)
	(bus
		(pts
			(xy 293.37 191.77) (xy 293.37 194.31)
		)
		(stroke
			(width 0)
			(type default)
		)
	)
	(wire
		(pts
			(xy 229.87 48.26) (xy 229.87 49.53)
		)
		(stroke
			(width 0)
			(type default)
		)
	)
	(wire
		(pts
			(xy 137.16 182.88) (xy 158.75 182.88)
		)
		(stroke
			(width 0)
			(type default)
		)
	)
	(wire
		(pts
			(xy 214.63 187.96) (xy 236.22 187.96)
		)
		(stroke
			(width 0)
			(type default)
		)
	)
	(bus
		(pts
			(xy 160.02 179.07) (xy 160.02 181.61)
		)
		(stroke
			(width 0)
			(type default)
		)
	)
	(wire
		(pts
			(xy 157.48 59.69) (xy 179.07 59.69)
		)
		(stroke
			(width 0)
			(type default)
		)
	)
	(wire
		(pts
			(xy 260.35 67.31) (xy 256.54 67.31)
		)
		(stroke
			(width 0)
			(type default)
		)
	)
	(wire
		(pts
			(xy 229.87 81.28) (xy 238.76 81.28)
		)
		(stroke
			(width 0)
			(type default)
		)
	)
	(bus
		(pts
			(xy 80.01 143.51) (xy 80.01 148.59)
		)
		(stroke
			(width 0)
			(type default)
		)
	)
	(bus
		(pts
			(xy 80.01 163.83) (xy 80.01 166.37)
		)
		(stroke
			(width 0)
			(type default)
		)
	)
	(bus
		(pts
			(xy 160.02 148.59) (xy 160.02 151.13)
		)
		(stroke
			(width 0)
			(type default)
		)
	)
	(wire
		(pts
			(xy 137.16 157.48) (xy 158.75 157.48)
		)
		(stroke
			(width 0)
			(type default)
		)
	)
	(wire
		(pts
			(xy 270.51 172.72) (xy 292.1 172.72)
		)
		(stroke
			(width 0)
			(type default)
		)
	)
	(wire
		(pts
			(xy 283.21 48.26) (xy 274.32 48.26)
		)
		(stroke
			(width 0)
			(type default)
		)
	)
	(wire
		(pts
			(xy 137.16 162.56) (xy 158.75 162.56)
		)
		(stroke
			(width 0)
			(type default)
		)
	)
	(wire
		(pts
			(xy 270.51 170.18) (xy 292.1 170.18)
		)
		(stroke
			(width 0)
			(type default)
		)
	)
	(wire
		(pts
			(xy 114.3 67.31) (xy 123.19 67.31)
		)
		(stroke
			(width 0)
			(type default)
		)
	)
	(wire
		(pts
			(xy 256.54 34.29) (xy 256.54 35.56)
		)
		(stroke
			(width 0)
			(type default)
		)
	)
	(bus
		(pts
			(xy 213.36 184.15) (xy 213.36 186.69)
		)
		(stroke
			(width 0)
			(type default)
		)
	)
	(wire
		(pts
			(xy 105.41 67.31) (xy 105.41 68.58)
		)
		(stroke
			(width 0)
			(type default)
		)
	)
	(wire
		(pts
			(xy 140.97 81.28) (xy 140.97 82.55)
		)
		(stroke
			(width 0)
			(type default)
		)
	)
	(wire
		(pts
			(xy 213.36 67.31) (xy 215.9 67.31)
		)
		(stroke
			(width 0)
			(type default)
		)
	)
	(bus
		(pts
			(xy 160.02 176.53) (xy 160.02 179.07)
		)
		(stroke
			(width 0)
			(type default)
		)
	)
	(bus
		(pts
			(xy 293.37 181.61) (xy 293.37 184.15)
		)
		(stroke
			(width 0)
			(type default)
		)
	)
	(wire
		(pts
			(xy 119.38 49.53) (xy 119.38 50.8)
		)
		(stroke
			(width 0)
			(type default)
		)
	)
	(wire
		(pts
			(xy 177.8 82.55) (xy 177.8 83.82)
		)
		(stroke
			(width 0)
			(type default)
		)
	)
	(bus
		(pts
			(xy 80.01 173.99) (xy 80.01 179.07)
		)
		(stroke
			(width 0)
			(type default)
		)
	)
	(bus
		(pts
			(xy 293.37 186.69) (xy 293.37 189.23)
		)
		(stroke
			(width 0)
			(type default)
		)
	)
	(bus
		(pts
			(xy 213.36 129.54) (xy 213.36 140.97)
		)
		(stroke
			(width 0)
			(type default)
		)
	)
	(wire
		(pts
			(xy 214.63 175.26) (xy 236.22 175.26)
		)
		(stroke
			(width 0)
			(type default)
		)
	)
	(bus
		(pts
			(xy 213.36 186.69) (xy 213.36 189.23)
		)
		(stroke
			(width 0)
			(type default)
		)
	)
	(bus
		(pts
			(xy 293.37 140.97) (xy 293.37 143.51)
		)
		(stroke
			(width 0)
			(type default)
		)
	)
	(bus
		(pts
			(xy 213.36 148.59) (xy 213.36 151.13)
		)
		(stroke
			(width 0)
			(type default)
		)
	)
	(wire
		(pts
			(xy 140.97 81.28) (xy 149.86 81.28)
		)
		(stroke
			(width 0)
			(type default)
		)
	)
	(wire
		(pts
			(xy 140.97 67.31) (xy 149.86 67.31)
		)
		(stroke
			(width 0)
			(type default)
		)
	)
	(wire
		(pts
			(xy 270.51 162.56) (xy 292.1 162.56)
		)
		(stroke
			(width 0)
			(type default)
		)
	)
	(bus
		(pts
			(xy 160.02 173.99) (xy 160.02 176.53)
		)
		(stroke
			(width 0)
			(type default)
		)
	)
	(wire
		(pts
			(xy 214.63 185.42) (xy 236.22 185.42)
		)
		(stroke
			(width 0)
			(type default)
		)
	)
	(bus
		(pts
			(xy 293.37 168.91) (xy 293.37 171.45)
		)
		(stroke
			(width 0)
			(type default)
		)
	)
	(bus
		(pts
			(xy 213.36 166.37) (xy 213.36 171.45)
		)
		(stroke
			(width 0)
			(type default)
		)
	)
	(wire
		(pts
			(xy 132.08 67.31) (xy 132.08 68.58)
		)
		(stroke
			(width 0)
			(type default)
		)
	)
	(wire
		(pts
			(xy 247.65 67.31) (xy 256.54 67.31)
		)
		(stroke
			(width 0)
			(type default)
		)
	)
	(wire
		(pts
			(xy 137.16 190.5) (xy 158.75 190.5)
		)
		(stroke
			(width 0)
			(type default)
		)
	)
	(wire
		(pts
			(xy 214.63 144.78) (xy 236.22 144.78)
		)
		(stroke
			(width 0)
			(type default)
		)
	)
	(wire
		(pts
			(xy 140.97 50.8) (xy 140.97 52.07)
		)
		(stroke
			(width 0)
			(type default)
		)
	)
	(bus
		(pts
			(xy 293.37 163.83) (xy 293.37 166.37)
		)
		(stroke
			(width 0)
			(type default)
		)
	)
	(bus
		(pts
			(xy 160.02 130.81) (xy 158.75 129.54)
		)
		(stroke
			(width 0)
			(type default)
		)
	)
	(wire
		(pts
			(xy 274.32 48.26) (xy 274.32 49.53)
		)
		(stroke
			(width 0)
			(type default)
		)
	)
	(wire
		(pts
			(xy 238.76 81.28) (xy 238.76 82.55)
		)
		(stroke
			(width 0)
			(type default)
		)
	)
	(wire
		(pts
			(xy 270.51 193.04) (xy 292.1 193.04)
		)
		(stroke
			(width 0)
			(type default)
		)
	)
	(bus
		(pts
			(xy 80.01 179.07) (xy 80.01 181.61)
		)
		(stroke
			(width 0)
			(type default)
		)
	)
	(wire
		(pts
			(xy 256.54 81.28) (xy 256.54 82.55)
		)
		(stroke
			(width 0)
			(type default)
		)
	)
	(bus
		(pts
			(xy 80.01 148.59) (xy 80.01 151.13)
		)
		(stroke
			(width 0)
			(type default)
		)
	)
	(wire
		(pts
			(xy 265.43 48.26) (xy 256.54 48.26)
		)
		(stroke
			(width 0)
			(type default)
		)
	)
	(wire
		(pts
			(xy 265.43 48.26) (xy 265.43 49.53)
		)
		(stroke
			(width 0)
			(type default)
		)
	)
	(bus
		(pts
			(xy 80.01 184.15) (xy 80.01 186.69)
		)
		(stroke
			(width 0)
			(type default)
		)
	)
	(wire
		(pts
			(xy 260.35 66.04) (xy 260.35 67.31)
		)
		(stroke
			(width 0)
			(type default)
		)
	)
	(wire
		(pts
			(xy 81.28 195.58) (xy 102.87 195.58)
		)
		(stroke
			(width 0)
			(type default)
		)
	)
	(bus
		(pts
			(xy 213.36 191.77) (xy 213.36 194.31)
		)
		(stroke
			(width 0)
			(type default)
		)
	)
	(wire
		(pts
			(xy 283.21 48.26) (xy 283.21 49.53)
		)
		(stroke
			(width 0)
			(type default)
		)
	)
	(wire
		(pts
			(xy 214.63 165.1) (xy 236.22 165.1)
		)
		(stroke
			(width 0)
			(type default)
		)
	)
	(bus
		(pts
			(xy 293.37 158.75) (xy 293.37 161.29)
		)
		(stroke
			(width 0)
			(type default)
		)
	)
	(wire
		(pts
			(xy 274.32 34.29) (xy 274.32 35.56)
		)
		(stroke
			(width 0)
			(type default)
		)
	)
	(wire
		(pts
			(xy 270.51 152.4) (xy 292.1 152.4)
		)
		(stroke
			(width 0)
			(type default)
		)
	)
	(bus
		(pts
			(xy 160.02 130.81) (xy 160.02 140.97)
		)
		(stroke
			(width 0)
			(type default)
		)
	)
	(wire
		(pts
			(xy 123.19 52.07) (xy 123.19 50.8)
		)
		(stroke
			(width 0)
			(type default)
		)
	)
	(wire
		(pts
			(xy 137.16 170.18) (xy 158.75 170.18)
		)
		(stroke
			(width 0)
			(type default)
		)
	)
	(wire
		(pts
			(xy 215.9 67.31) (xy 229.87 67.31)
		)
		(stroke
			(width 0)
			(type default)
		)
	)
	(wire
		(pts
			(xy 81.28 180.34) (xy 102.87 180.34)
		)
		(stroke
			(width 0)
			(type default)
		)
	)
	(bus
		(pts
			(xy 213.36 151.13) (xy 213.36 156.21)
		)
		(stroke
			(width 0)
			(type default)
		)
	)
	(bus
		(pts
			(xy 80.01 189.23) (xy 80.01 191.77)
		)
		(stroke
			(width 0)
			(type default)
		)
	)
	(wire
		(pts
			(xy 247.65 67.31) (xy 247.65 68.58)
		)
		(stroke
			(width 0)
			(type default)
		)
	)
	(bus
		(pts
			(xy 80.01 129.54) (xy 80.01 140.97)
		)
		(stroke
			(width 0)
			(type default)
		)
	)
	(wire
		(pts
			(xy 265.43 34.29) (xy 256.54 34.29)
		)
		(stroke
			(width 0)
			(type default)
		)
	)
	(wire
		(pts
			(xy 137.16 180.34) (xy 158.75 180.34)
		)
		(stroke
			(width 0)
			(type default)
		)
	)
	(wire
		(pts
			(xy 81.28 160.02) (xy 102.87 160.02)
		)
		(stroke
			(width 0)
			(type default)
		)
	)
	(bus
		(pts
			(xy 80.01 129.54) (xy 74.93 129.54)
		)
		(stroke
			(width 0)
			(type default)
		)
	)
	(wire
		(pts
			(xy 132.08 81.28) (xy 132.08 82.55)
		)
		(stroke
			(width 0)
			(type default)
		)
	)
	(wire
		(pts
			(xy 265.43 34.29) (xy 265.43 35.56)
		)
		(stroke
			(width 0)
			(type default)
		)
	)
	(wire
		(pts
			(xy 137.16 149.86) (xy 158.75 149.86)
		)
		(stroke
			(width 0)
			(type default)
		)
	)
	(bus
		(pts
			(xy 80.01 186.69) (xy 80.01 189.23)
		)
		(stroke
			(width 0)
			(type default)
		)
	)
	(bus
		(pts
			(xy 293.37 176.53) (xy 293.37 179.07)
		)
		(stroke
			(width 0)
			(type default)
		)
	)
	(bus
		(pts
			(xy 80.01 140.97) (xy 80.01 143.51)
		)
		(stroke
			(width 0)
			(type default)
		)
	)
	(wire
		(pts
			(xy 81.28 142.24) (xy 102.87 142.24)
		)
		(stroke
			(width 0)
			(type default)
		)
	)
	(bus
		(pts
			(xy 80.01 181.61) (xy 80.01 184.15)
		)
		(stroke
			(width 0)
			(type default)
		)
	)
	(wire
		(pts
			(xy 247.65 81.28) (xy 247.65 82.55)
		)
		(stroke
			(width 0)
			(type default)
		)
	)
	(wire
		(pts
			(xy 222.25 34.29) (xy 229.87 34.29)
		)
		(stroke
			(width 0)
			(type default)
		)
	)
	(wire
		(pts
			(xy 114.3 81.28) (xy 114.3 82.55)
		)
		(stroke
			(width 0)
			(type default)
		)
	)
	(bus
		(pts
			(xy 213.36 129.54) (xy 292.1 129.54)
		)
		(stroke
			(width 0)
			(type default)
		)
	)
	(wire
		(pts
			(xy 214.63 157.48) (xy 236.22 157.48)
		)
		(stroke
			(width 0)
			(type default)
		)
	)
	(wire
		(pts
			(xy 81.28 165.1) (xy 102.87 165.1)
		)
		(stroke
			(width 0)
			(type default)
		)
	)
	(wire
		(pts
			(xy 238.76 34.29) (xy 238.76 35.56)
		)
		(stroke
			(width 0)
			(type default)
		)
	)
	(wire
		(pts
			(xy 132.08 81.28) (xy 140.97 81.28)
		)
		(stroke
			(width 0)
			(type default)
		)
	)
	(bus
		(pts
			(xy 160.02 143.51) (xy 160.02 148.59)
		)
		(stroke
			(width 0)
			(type default)
		)
	)
	(bus
		(pts
			(xy 80.01 156.21) (xy 80.01 158.75)
		)
		(stroke
			(width 0)
			(type default)
		)
	)
	(wire
		(pts
			(xy 81.28 172.72) (xy 102.87 172.72)
		)
		(stroke
			(width 0)
			(type default)
		)
	)
	(bus
		(pts
			(xy 160.02 156.21) (xy 160.02 158.75)
		)
		(stroke
			(width 0)
			(type default)
		)
	)
	(wire
		(pts
			(xy 270.51 142.24) (xy 292.1 142.24)
		)
		(stroke
			(width 0)
			(type default)
		)
	)
	(wire
		(pts
			(xy 137.16 144.78) (xy 158.75 144.78)
		)
		(stroke
			(width 0)
			(type default)
		)
	)
	(wire
		(pts
			(xy 229.87 48.26) (xy 222.25 48.26)
		)
		(stroke
			(width 0)
			(type default)
		)
	)
	(wire
		(pts
			(xy 214.63 142.24) (xy 236.22 142.24)
		)
		(stroke
			(width 0)
			(type default)
		)
	)
	(wire
		(pts
			(xy 179.07 53.34) (xy 168.91 53.34)
		)
		(stroke
			(width 0)
			(type default)
		)
	)
	(wire
		(pts
			(xy 157.48 50.8) (xy 157.48 59.69)
		)
		(stroke
			(width 0)
			(type default)
		)
	)
	(wire
		(pts
			(xy 270.51 167.64) (xy 292.1 167.64)
		)
		(stroke
			(width 0)
			(type default)
		)
	)
	(wire
		(pts
			(xy 137.16 152.4) (xy 158.75 152.4)
		)
		(stroke
			(width 0)
			(type default)
		)
	)
	(wire
		(pts
			(xy 105.41 81.28) (xy 114.3 81.28)
		)
		(stroke
			(width 0)
			(type default)
		)
	)
	(wire
		(pts
			(xy 137.16 142.24) (xy 158.75 142.24)
		)
		(stroke
			(width 0)
			(type default)
		)
	)
	(wire
		(pts
			(xy 105.41 81.28) (xy 105.41 82.55)
		)
		(stroke
			(width 0)
			(type default)
		)
	)
	(wire
		(pts
			(xy 179.07 74.93) (xy 170.18 74.93)
		)
		(stroke
			(width 0)
			(type default)
		)
	)
	(wire
		(pts
			(xy 114.3 81.28) (xy 123.19 81.28)
		)
		(stroke
			(width 0)
			(type default)
		)
	)
	(bus
		(pts
			(xy 293.37 184.15) (xy 293.37 186.69)
		)
		(stroke
			(width 0)
			(type default)
		)
	)
	(bus
		(pts
			(xy 293.37 156.21) (xy 293.37 158.75)
		)
		(stroke
			(width 0)
			(type default)
		)
	)
	(wire
		(pts
			(xy 270.51 195.58) (xy 292.1 195.58)
		)
		(stroke
			(width 0)
			(type default)
		)
	)
	(wire
		(pts
			(xy 123.19 67.31) (xy 132.08 67.31)
		)
		(stroke
			(width 0)
			(type default)
		)
	)
	(wire
		(pts
			(xy 149.86 81.28) (xy 149.86 82.55)
		)
		(stroke
			(width 0)
			(type default)
		)
	)
	(bus
		(pts
			(xy 213.36 129.54) (xy 208.28 129.54)
		)
		(stroke
			(width 0)
			(type default)
		)
	)
	(wire
		(pts
			(xy 214.63 172.72) (xy 236.22 172.72)
		)
		(stroke
			(width 0)
			(type default)
		)
	)
	(wire
		(pts
			(xy 132.08 50.8) (xy 132.08 52.07)
		)
		(stroke
			(width 0)
			(type default)
		)
	)
	(wire
		(pts
			(xy 274.32 48.26) (xy 265.43 48.26)
		)
		(stroke
			(width 0)
			(type default)
		)
	)
	(wire
		(pts
			(xy 214.63 190.5) (xy 236.22 190.5)
		)
		(stroke
			(width 0)
			(type default)
		)
	)
	(wire
		(pts
			(xy 214.63 160.02) (xy 236.22 160.02)
		)
		(stroke
			(width 0)
			(type default)
		)
	)
	(wire
		(pts
			(xy 270.51 157.48) (xy 292.1 157.48)
		)
		(stroke
			(width 0)
			(type default)
		)
	)
	(bus
		(pts
			(xy 80.01 129.54) (xy 158.75 129.54)
		)
		(stroke
			(width 0)
			(type default)
		)
	)
	(wire
		(pts
			(xy 270.51 165.1) (xy 292.1 165.1)
		)
		(stroke
			(width 0)
			(type default)
		)
	)
	(bus
		(pts
			(xy 160.02 184.15) (xy 160.02 186.69)
		)
		(stroke
			(width 0)
			(type default)
		)
	)
	(bus
		(pts
			(xy 213.36 181.61) (xy 213.36 184.15)
		)
		(stroke
			(width 0)
			(type default)
		)
	)
	(wire
		(pts
			(xy 256.54 67.31) (xy 256.54 68.58)
		)
		(stroke
			(width 0)
			(type default)
		)
	)
	(bus
		(pts
			(xy 293.37 189.23) (xy 293.37 191.77)
		)
		(stroke
			(width 0)
			(type default)
		)
	)
	(wire
		(pts
			(xy 215.9 34.29) (xy 222.25 34.29)
		)
		(stroke
			(width 0)
			(type default)
		)
	)
	(wire
		(pts
			(xy 81.28 185.42) (xy 102.87 185.42)
		)
		(stroke
			(width 0)
			(type default)
		)
	)
	(wire
		(pts
			(xy 287.02 34.29) (xy 283.21 34.29)
		)
		(stroke
			(width 0)
			(type default)
		)
	)
	(wire
		(pts
			(xy 247.65 48.26) (xy 238.76 48.26)
		)
		(stroke
			(width 0)
			(type default)
		)
	)
	(wire
		(pts
			(xy 214.63 193.04) (xy 236.22 193.04)
		)
		(stroke
			(width 0)
			(type default)
		)
	)
	(bus
		(pts
			(xy 213.36 156.21) (xy 213.36 158.75)
		)
		(stroke
			(width 0)
			(type default)
		)
	)
	(wire
		(pts
			(xy 229.87 34.29) (xy 229.87 35.56)
		)
		(stroke
			(width 0)
			(type default)
		)
	)
	(wire
		(pts
			(xy 81.28 187.96) (xy 102.87 187.96)
		)
		(stroke
			(width 0)
			(type default)
		)
	)
	(wire
		(pts
			(xy 81.28 193.04) (xy 102.87 193.04)
		)
		(stroke
			(width 0)
			(type default)
		)
	)
	(wire
		(pts
			(xy 137.16 195.58) (xy 158.75 195.58)
		)
		(stroke
			(width 0)
			(type default)
		)
	)
	(bus
		(pts
			(xy 293.37 148.59) (xy 293.37 151.13)
		)
		(stroke
			(width 0)
			(type default)
		)
	)
	(wire
		(pts
			(xy 229.87 81.28) (xy 229.87 82.55)
		)
		(stroke
			(width 0)
			(type default)
		)
	)
	(label "LPDDR5_A.WCK0_P"
		(at 82.55 157.48 0)
		(effects
			(font
				(size 1.27 1.27)
			)
			(justify left bottom)
		)
	)
	(label "LPDDR5_A.DQ10"
		(at 138.43 182.88 0)
		(effects
			(font
				(size 1.27 1.27)
			)
			(justify left bottom)
		)
	)
	(label "LPDDR5_B.CA5"
		(at 216.535 193.04 0)
		(effects
			(font
				(size 1.27 1.27)
			)
			(justify left bottom)
		)
	)
	(label "LPDDR5_B.DQ7"
		(at 271.78 175.26 0)
		(effects
			(font
				(size 1.27 1.27)
			)
			(justify left bottom)
		)
	)
	(label "LPDDR5_A.DQ6"
		(at 138.43 172.72 0)
		(effects
			(font
				(size 1.27 1.27)
			)
			(justify left bottom)
		)
	)
	(label "LPDDR5_A.CA1"
		(at 82.55 182.88 0)
		(effects
			(font
				(size 1.27 1.27)
			)
			(justify left bottom)
		)
	)
	(label "LPDDR5_A.DQ0"
		(at 138.43 157.48 0)
		(effects
			(font
				(size 1.27 1.27)
			)
			(justify left bottom)
		)
	)
	(label "LPDDR5_A.DQ13"
		(at 138.43 190.5 0)
		(effects
			(font
				(size 1.27 1.27)
			)
			(justify left bottom)
		)
	)
	(label "LPDDR5_B.DQ14"
		(at 271.78 193.04 0)
		(effects
			(font
				(size 1.27 1.27)
			)
			(justify left bottom)
		)
	)
	(label "LPDDR5_A.DMI0"
		(at 82.55 149.86 0)
		(effects
			(font
				(size 1.27 1.27)
			)
			(justify left bottom)
		)
	)
	(label "LPDDR5_A.CS0"
		(at 82.55 142.24 0)
		(effects
			(font
				(size 1.27 1.27)
			)
			(justify left bottom)
		)
	)
	(label "LPDDR5_B.DQ6"
		(at 271.78 172.72 0)
		(effects
			(font
				(size 1.27 1.27)
			)
			(justify left bottom)
		)
	)
	(label "LPDDR5_B.RDQS1_N"
		(at 271.78 152.4 0)
		(effects
			(font
				(size 1.27 1.27)
			)
			(justify left bottom)
		)
	)
	(label "LPDDR5_B.CS0"
		(at 216.535 142.24 0)
		(effects
			(font
				(size 1.27 1.27)
			)
			(justify left bottom)
		)
	)
	(label "LPDDR5_B.DMI1"
		(at 216.535 152.4 0)
		(effects
			(font
				(size 1.27 1.27)
			)
			(justify left bottom)
		)
	)
	(label "LPDDR5_A.WCK1_N"
		(at 82.55 167.64 0)
		(effects
			(font
				(size 1.27 1.27)
			)
			(justify left bottom)
		)
	)
	(label "LPDDR5_B.WCK0_P"
		(at 216.535 157.48 0)
		(effects
			(font
				(size 1.27 1.27)
			)
			(justify left bottom)
		)
	)
	(label "LPDDR5_A.RDQS0_N"
		(at 138.43 144.78 0)
		(effects
			(font
				(size 1.27 1.27)
			)
			(justify left bottom)
		)
	)
	(label "LPDDR5_A.CK_N"
		(at 82.55 175.26 0)
		(effects
			(font
				(size 1.27 1.27)
			)
			(justify left bottom)
		)
	)
	(label "LPDDR5_A.DQ12"
		(at 138.43 187.96 0)
		(effects
			(font
				(size 1.27 1.27)
			)
			(justify left bottom)
		)
	)
	(label "LPDDR5_B.RDQS0_N"
		(at 271.78 144.78 0)
		(effects
			(font
				(size 1.27 1.27)
			)
			(justify left bottom)
		)
	)
	(label "LPDDR5_A.DQ7"
		(at 138.43 175.26 0)
		(effects
			(font
				(size 1.27 1.27)
			)
			(justify left bottom)
		)
	)
	(label "LPDDR5_A.RDQS0_P"
		(at 138.43 142.24 0)
		(effects
			(font
				(size 1.27 1.27)
			)
			(justify left bottom)
		)
	)
	(label "LPDDR5_B.WCK1_N"
		(at 216.535 167.64 0)
		(effects
			(font
				(size 1.27 1.27)
			)
			(justify left bottom)
		)
	)
	(label "LPDDR5_B.DMI0"
		(at 216.535 149.86 0)
		(effects
			(font
				(size 1.27 1.27)
			)
			(justify left bottom)
		)
	)
	(label "LPDDR5_B.DQ9"
		(at 271.78 180.34 0)
		(effects
			(font
				(size 1.27 1.27)
			)
			(justify left bottom)
		)
	)
	(label "LPDDR5_A.CA3"
		(at 82.55 187.96 0)
		(effects
			(font
				(size 1.27 1.27)
			)
			(justify left bottom)
		)
	)
	(label "LPDDR5_A.DQ1"
		(at 138.43 160.02 0)
		(effects
			(font
				(size 1.27 1.27)
			)
			(justify left bottom)
		)
	)
	(label "LPDDR5_A.DQ15"
		(at 138.43 195.58 0)
		(effects
			(font
				(size 1.27 1.27)
			)
			(justify left bottom)
		)
	)
	(label "LPDDR5_B.CK_N"
		(at 216.535 175.26 0)
		(effects
			(font
				(size 1.27 1.27)
			)
			(justify left bottom)
		)
	)
	(label "LPDDR5_B.CA4"
		(at 216.535 190.5 0)
		(effects
			(font
				(size 1.27 1.27)
			)
			(justify left bottom)
		)
	)
	(label "LPDDR5_A.DQ8"
		(at 138.43 177.8 0)
		(effects
			(font
				(size 1.27 1.27)
			)
			(justify left bottom)
		)
	)
	(label "LPDDR5_B.CA1"
		(at 216.535 182.88 0)
		(effects
			(font
				(size 1.27 1.27)
			)
			(justify left bottom)
		)
	)
	(label "LPDDR5_B.DQ15"
		(at 271.78 195.58 0)
		(effects
			(font
				(size 1.27 1.27)
			)
			(justify left bottom)
		)
	)
	(label "LPDDR5_B.CA0"
		(at 216.535 180.34 0)
		(effects
			(font
				(size 1.27 1.27)
			)
			(justify left bottom)
		)
	)
	(label "LPDDR5_A.DQ3"
		(at 138.43 165.1 0)
		(effects
			(font
				(size 1.27 1.27)
			)
			(justify left bottom)
		)
	)
	(label "LPDDR5_A.DMI1"
		(at 82.55 152.4 0)
		(effects
			(font
				(size 1.27 1.27)
			)
			(justify left bottom)
		)
	)
	(label "LPDDR5_B.CA2"
		(at 216.535 185.42 0)
		(effects
			(font
				(size 1.27 1.27)
			)
			(justify left bottom)
		)
	)
	(label "LPDDR5_A.CA2"
		(at 82.55 185.42 0)
		(effects
			(font
				(size 1.27 1.27)
			)
			(justify left bottom)
		)
	)
	(label "LPDDR5_B.CA3"
		(at 216.535 187.96 0)
		(effects
			(font
				(size 1.27 1.27)
			)
			(justify left bottom)
		)
	)
	(label "LPDDR5_A.RDQS1_N"
		(at 138.43 152.4 0)
		(effects
			(font
				(size 1.27 1.27)
			)
			(justify left bottom)
		)
	)
	(label "LPDDR5_A.DQ11"
		(at 138.43 185.42 0)
		(effects
			(font
				(size 1.27 1.27)
			)
			(justify left bottom)
		)
	)
	(label "LPDDR5_A.WCK1_P"
		(at 82.55 165.1 0)
		(effects
			(font
				(size 1.27 1.27)
			)
			(justify left bottom)
		)
	)
	(label "LPDDR5_A.DQ9"
		(at 138.43 180.34 0)
		(effects
			(font
				(size 1.27 1.27)
			)
			(justify left bottom)
		)
	)
	(label "LPDDR5_A.CA4"
		(at 82.55 190.5 0)
		(effects
			(font
				(size 1.27 1.27)
			)
			(justify left bottom)
		)
	)
	(label "LPDDR5_B.RDQS1_P"
		(at 271.78 149.86 0)
		(effects
			(font
				(size 1.27 1.27)
			)
			(justify left bottom)
		)
	)
	(label "LPDDR5_B.CS1"
		(at 216.535 144.78 0)
		(effects
			(font
				(size 1.27 1.27)
			)
			(justify left bottom)
		)
	)
	(label "LPDDR5_A.CA6"
		(at 82.55 195.58 0)
		(effects
			(font
				(size 1.27 1.27)
			)
			(justify left bottom)
		)
	)
	(label "LPDDR5_B.RDQS0_P"
		(at 271.78 142.24 0)
		(effects
			(font
				(size 1.27 1.27)
			)
			(justify left bottom)
		)
	)
	(label "LPDDR5_A.DQ5"
		(at 138.43 170.18 0)
		(effects
			(font
				(size 1.27 1.27)
			)
			(justify left bottom)
		)
	)
	(label "LPDDR5_B.WCK0_N"
		(at 216.535 160.02 0)
		(effects
			(font
				(size 1.27 1.27)
			)
			(justify left bottom)
		)
	)
	(label "LPDDR5_B.DQ12"
		(at 271.78 187.96 0)
		(effects
			(font
				(size 1.27 1.27)
			)
			(justify left bottom)
		)
	)
	(label "LPDDR5_B.DQ0"
		(at 271.78 157.48 0)
		(effects
			(font
				(size 1.27 1.27)
			)
			(justify left bottom)
		)
	)
	(label "LPDDR5_B.DQ2"
		(at 271.78 162.56 0)
		(effects
			(font
				(size 1.27 1.27)
			)
			(justify left bottom)
		)
	)
	(label "LPDDR5_B.DQ3"
		(at 271.78 165.1 0)
		(effects
			(font
				(size 1.27 1.27)
			)
			(justify left bottom)
		)
	)
	(label "LPDDR5_A.DQ4"
		(at 138.43 167.64 0)
		(effects
			(font
				(size 1.27 1.27)
			)
			(justify left bottom)
		)
	)
	(label "LPDDR5_A.RDQS1_P"
		(at 138.43 149.86 0)
		(effects
			(font
				(size 1.27 1.27)
			)
			(justify left bottom)
		)
	)
	(label "LPDDR5_A.DQ14"
		(at 138.43 193.04 0)
		(effects
			(font
				(size 1.27 1.27)
			)
			(justify left bottom)
		)
	)
	(label "LPDDR5_B.DQ11"
		(at 271.78 185.42 0)
		(effects
			(font
				(size 1.27 1.27)
			)
			(justify left bottom)
		)
	)
	(label "LPDDR5_B.DQ5"
		(at 271.78 170.18 0)
		(effects
			(font
				(size 1.27 1.27)
			)
			(justify left bottom)
		)
	)
	(label "LPDDR5_A.CK_P"
		(at 82.55 172.72 0)
		(effects
			(font
				(size 1.27 1.27)
			)
			(justify left bottom)
		)
	)
	(label "LPDDR5_B.CK_P"
		(at 216.535 172.72 0)
		(effects
			(font
				(size 1.27 1.27)
			)
			(justify left bottom)
		)
	)
	(label "LPDDR5_A.WCK0_N"
		(at 82.55 160.02 0)
		(effects
			(font
				(size 1.27 1.27)
			)
			(justify left bottom)
		)
	)
	(label "LPDDR5_B.CA6"
		(at 216.535 195.58 0)
		(effects
			(font
				(size 1.27 1.27)
			)
			(justify left bottom)
		)
	)
	(label "LPDDR5_A.CA0"
		(at 82.55 180.34 0)
		(effects
			(font
				(size 1.27 1.27)
			)
			(justify left bottom)
		)
	)
	(label "LPDDR5_B.DQ1"
		(at 271.78 160.02 0)
		(effects
			(font
				(size 1.27 1.27)
			)
			(justify left bottom)
		)
	)
	(label "LPDDR5_B.DQ10"
		(at 271.78 182.88 0)
		(effects
			(font
				(size 1.27 1.27)
			)
			(justify left bottom)
		)
	)
	(label "LPDDR5_A.CS1"
		(at 82.55 144.78 0)
		(effects
			(font
				(size 1.27 1.27)
			)
			(justify left bottom)
		)
	)
	(label "LPDDR5_B.DQ13"
		(at 271.78 190.5 0)
		(effects
			(font
				(size 1.27 1.27)
			)
			(justify left bottom)
		)
	)
	(label "LPDDR5_B.DQ8"
		(at 271.78 177.8 0)
		(effects
			(font
				(size 1.27 1.27)
			)
			(justify left bottom)
		)
	)
	(label "LPDDR5_B.DQ4"
		(at 271.78 167.64 0)
		(effects
			(font
				(size 1.27 1.27)
			)
			(justify left bottom)
		)
	)
	(label "LPDDR5_B.WCK1_P"
		(at 216.535 165.1 0)
		(effects
			(font
				(size 1.27 1.27)
			)
			(justify left bottom)
		)
	)
	(label "LPDDR5_A.CA5"
		(at 82.55 193.04 0)
		(effects
			(font
				(size 1.27 1.27)
			)
			(justify left bottom)
		)
	)
	(label "LPDDR5_A.DQ2"
		(at 138.43 162.56 0)
		(effects
			(font
				(size 1.27 1.27)
			)
			(justify left bottom)
		)
	)
	(hierarchical_label "~{RESET}"
		(shape input)
		(at 168.91 53.34 180)
		(effects
			(font
				(size 1.27 1.27)
			)
			(justify right)
		)
	)
	(hierarchical_label "LPDDR5_A{LPDDR5}"
		(shape bidirectional)
		(at 74.93 129.54 180)
		(effects
			(font
				(size 1.27 1.27)
			)
			(justify right)
		)
	)
	(hierarchical_label "LPDDR5_B{LPDDR5}"
		(shape bidirectional)
		(at 208.28 129.54 180)
		(effects
			(font
				(size 1.27 1.27)
			)
			(justify right)
		)
	)
	(symbol
		(lib_id "antmicroCapacitors0402:C_4u7_0402")
		(at 238.76 40.64 270)
		(mirror x)
		(unit 1)
		(exclude_from_sim no)
		(in_bom yes)
		(on_board yes)
		(dnp no)
		(fields_autoplaced yes)
		(property "Reference" "C57"
			(at 236.22 36.8235 90)
			(effects
				(font
					(size 1.27 1.27)
					(thickness 0.15)
				)
				(justify right)
			)
		)
		(property "Value" "C_4u7_0402"
			(at 228.6 20.32 0)
			(effects
				(font
					(size 1.27 1.27)
					(thickness 0.15)
				)
				(justify left bottom)
				(hide yes)
			)
		)
		(property "Footprint" "antmicro-footprints:C_0402_1005Metric"
			(at 226.06 20.32 0)
			(effects
				(font
					(size 1.27 1.27)
					(thickness 0.15)
				)
				(justify left bottom)
				(hide yes)
			)
		)
		(property "Datasheet" "https://www.murata.com/products/productdetail?partno=GRM155R61A475MEAA%23"
			(at 223.52 20.32 0)
			(effects
				(font
					(size 1.27 1.27)
					(thickness 0.15)
				)
				(justify left bottom)
				(hide yes)
			)
		)
		(property "Description" ""
			(at 238.76 40.64 0)
			(effects
				(font
					(size 1.27 1.27)
				)
			)
		)
		(property "MPN" "GRM155R61A475MEAAD"
			(at 220.98 20.32 0)
			(effects
				(font
					(size 1.27 1.27)
					(thickness 0.15)
				)
				(justify left bottom)
				(hide yes)
			)
		)
		(property "Manufacturer" "Murata"
			(at 218.44 20.32 0)
			(effects
				(font
					(size 1.27 1.27)
					(thickness 0.15)
				)
				(justify left bottom)
				(hide yes)
			)
		)
		(property "License" "Apache-2.0"
			(at 215.9 20.32 0)
			(effects
				(font
					(size 1.27 1.27)
					(thickness 0.15)
				)
				(justify left bottom)
				(hide yes)
			)
		)
		(property "Author" "Antmicro"
			(at 213.36 20.32 0)
			(effects
				(font
					(size 1.27 1.27)
					(thickness 0.15)
				)
				(justify left bottom)
				(hide yes)
			)
		)
		(property "Val" "4u7"
			(at 236.22 39.3635 90)
			(effects
				(font
					(size 1.27 1.27)
					(thickness 0.15)
				)
				(justify right)
			)
		)
		(property "Voltage" ""
			(at 210.82 20.32 0)
			(effects
				(font
					(size 1.27 1.27)
				)
				(justify left bottom)
				(hide yes)
			)
		)
		(property "Dielectric" ""
			(at 208.28 20.32 0)
			(effects
				(font
					(size 1.27 1.27)
				)
				(justify left bottom)
				(hide yes)
			)
		)
		(pin "1"
		)
		(pin "2"
		)
		(instances
			(project ""
				(path ""
					(reference "C57")
					(unit 1)
				)
			)
		)
	)
	(symbol
		(lib_id "antmicropower:GND")
		(at 265.43 40.64 0)
		(mirror y)
		(unit 1)
		(exclude_from_sim no)
		(in_bom yes)
		(on_board yes)
		(dnp no)
		(property "Reference" "#PWR0199"
			(at 265.43 46.99 0)
			(effects
				(font
					(size 1.27 1.27)
				)
				(hide yes)
			)
		)
		(property "Value" "GND"
			(at 265.43 44.45 0)
			(effects
				(font
					(size 1.27 1.27)
				)
			)
		)
		(property "Footprint" ""
			(at 265.43 40.64 0)
			(effects
				(font
					(size 1.27 1.27)
				)
				(hide yes)
			)
		)
		(property "Datasheet" ""
			(at 265.43 40.64 0)
			(effects
				(font
					(size 1.27 1.27)
				)
				(hide yes)
			)
		)
		(property "Description" ""
			(at 265.43 40.64 0)
			(effects
				(font
					(size 1.27 1.27)
				)
			)
		)
		(pin "1"
		)
		(instances
			(project ""
				(path ""
					(reference "#PWR0199")
					(unit 1)
				)
			)
		)
	)
	(symbol
		(lib_id "antmicroCapacitors0402:C_4u7_0402")
		(at 238.76 73.66 90)
		(unit 1)
		(exclude_from_sim no)
		(in_bom yes)
		(on_board yes)
		(dnp no)
		(fields_autoplaced yes)
		(property "Reference" "C55"
			(at 241.3 69.8435 90)
			(effects
				(font
					(size 1.27 1.27)
					(thickness 0.15)
				)
				(justify right)
			)
		)
		(property "Value" "C_4u7_0402"
			(at 248.92 53.34 0)
			(effects
				(font
					(size 1.27 1.27)
					(thickness 0.15)
				)
				(justify left bottom)
				(hide yes)
			)
		)
		(property "Footprint" "antmicro-footprints:C_0402_1005Metric"
			(at 251.46 53.34 0)
			(effects
				(font
					(size 1.27 1.27)
					(thickness 0.15)
				)
				(justify left bottom)
				(hide yes)
			)
		)
		(property "Datasheet" "https://www.murata.com/products/productdetail?partno=GRM155R61A475MEAA%23"
			(at 254 53.34 0)
			(effects
				(font
					(size 1.27 1.27)
					(thickness 0.15)
				)
				(justify left bottom)
				(hide yes)
			)
		)
		(property "Description" ""
			(at 238.76 73.66 0)
			(effects
				(font
					(size 1.27 1.27)
				)
			)
		)
		(property "MPN" "GRM155R61A475MEAAD"
			(at 256.54 53.34 0)
			(effects
				(font
					(size 1.27 1.27)
					(thickness 0.15)
				)
				(justify left bottom)
				(hide yes)
			)
		)
		(property "Manufacturer" "Murata"
			(at 259.08 53.34 0)
			(effects
				(font
					(size 1.27 1.27)
					(thickness 0.15)
				)
				(justify left bottom)
				(hide yes)
			)
		)
		(property "License" "Apache-2.0"
			(at 261.62 53.34 0)
			(effects
				(font
					(size 1.27 1.27)
					(thickness 0.15)
				)
				(justify left bottom)
				(hide yes)
			)
		)
		(property "Author" "Antmicro"
			(at 264.16 53.34 0)
			(effects
				(font
					(size 1.27 1.27)
					(thickness 0.15)
				)
				(justify left bottom)
				(hide yes)
			)
		)
		(property "Val" "4u7"
			(at 241.3 72.3835 90)
			(effects
				(font
					(size 1.27 1.27)
					(thickness 0.15)
				)
				(justify right)
			)
		)
		(property "Voltage" ""
			(at 266.7 53.34 0)
			(effects
				(font
					(size 1.27 1.27)
				)
				(justify left bottom)
				(hide yes)
			)
		)
		(property "Dielectric" ""
			(at 269.24 53.34 0)
			(effects
				(font
					(size 1.27 1.27)
				)
				(justify left bottom)
				(hide yes)
			)
		)
		(pin "1"
		)
		(pin "2"
		)
		(instances
			(project ""
				(path ""
					(reference "C55")
					(unit 1)
				)
			)
		)
	)
	(symbol
		(lib_id "antmicropower:GND")
		(at 149.86 73.66 0)
		(unit 1)
		(exclude_from_sim no)
		(in_bom yes)
		(on_board yes)
		(dnp no)
		(property "Reference" "#PWR0170"
			(at 149.86 80.01 0)
			(effects
				(font
					(size 1.27 1.27)
				)
				(hide yes)
			)
		)
		(property "Value" "GND"
			(at 149.86 77.47 0)
			(effects
				(font
					(size 1.27 1.27)
				)
			)
		)
		(property "Footprint" ""
			(at 149.86 73.66 0)
			(effects
				(font
					(size 1.27 1.27)
				)
				(hide yes)
			)
		)
		(property "Datasheet" ""
			(at 149.86 73.66 0)
			(effects
				(font
					(size 1.27 1.27)
				)
				(hide yes)
			)
		)
		(property "Description" ""
			(at 149.86 73.66 0)
			(effects
				(font
					(size 1.27 1.27)
				)
			)
		)
		(pin "1"
		)
		(instances
			(project ""
				(path ""
					(reference "#PWR0170")
					(unit 1)
				)
			)
		)
	)
	(symbol
		(lib_id "antmicroMemory:MT62F1G32D4DR-031")
		(at 102.87 142.24 0)
		(unit 2)
		(exclude_from_sim no)
		(in_bom yes)
		(on_board yes)
		(dnp no)
		(fields_autoplaced yes)
		(property "Reference" "U1"
			(at 120.015 133.985 0)
			(effects
				(font
					(size 1.27 1.27)
				)
			)
		)
		(property "Value" "MT62F1G32D4DR-031"
			(at 147.32 147.32 0)
			(effects
				(font
					(size 1.27 1.27)
				)
				(justify left bottom)
				(hide yes)
			)
		)
		(property "Footprint" "antmicro-footprints:BGA-315_12.4x15mm_Layout15x21_P0.8x0.7mm"
			(at 147.32 154.94 0)
			(effects
				(font
					(size 1.27 1.27)
				)
				(justify left bottom)
				(hide yes)
			)
		)
		(property "Datasheet" "https://www.micron.com/search-results?searchRequest=%7B%22term%22%3A%22MT62F1G32D4DR-031%22%7D"
			(at 147.32 152.4 0)
			(effects
				(font
					(size 1.27 1.27)
				)
				(justify left bottom)
				(hide yes)
			)
		)
		(property "Description" ""
			(at 102.87 142.24 0)
			(effects
				(font
					(size 1.27 1.27)
				)
			)
		)
		(property "Manufacturer" "Micron Technology"
			(at 147.32 149.86 0)
			(effects
				(font
					(size 1.27 1.27)
				)
				(justify left bottom)
				(hide yes)
			)
		)
		(property "MPN" "MT62F1G32D4DR-031 WT:B"
			(at 120.015 136.525 0)
			(effects
				(font
					(size 1.27 1.27)
				)
			)
		)
		(property "Author" "Antmicro"
			(at 147.32 157.48 0)
			(effects
				(font
					(size 1.27 1.27)
				)
				(justify left bottom)
				(hide yes)
			)
		)
		(property "License" "Apache-2.0"
			(at 147.32 160.02 0)
			(effects
				(font
					(size 1.27 1.27)
				)
				(justify left bottom)
				(hide yes)
			)
		)
		(pin "A1"
		)
		(pin "A10"
		)
		(pin "A11"
		)
		(pin "A13"
		)
		(pin "A14"
		)
		(pin "A15"
		)
		(pin "A2"
		)
		(pin "A3"
		)
		(pin "A5"
		)
		(pin "A6"
		)
		(pin "A7"
		)
		(pin "A8"
		)
		(pin "A9"
		)
		(pin "AA1"
		)
		(pin "AA10"
		)
		(pin "AA11"
		)
		(pin "AA13"
		)
		(pin "AA14"
		)
		(pin "AA15"
		)
		(pin "AA2"
		)
		(pin "AA3"
		)
		(pin "AA5"
		)
		(pin "AA6"
		)
		(pin "AA7"
		)
		(pin "AA8"
		)
		(pin "AA9"
		)
		(pin "B1"
		)
		(pin "B10"
		)
		(pin "B12"
		)
		(pin "B14"
		)
		(pin "B15"
		)
		(pin "B2"
		)
		(pin "B4"
		)
		(pin "B6"
		)
		(pin "B7"
		)
		(pin "B8"
		)
		(pin "B9"
		)
		(pin "C1"
		)
		(pin "C11"
		)
		(pin "C13"
		)
		(pin "C15"
		)
		(pin "C3"
		)
		(pin "C5"
		)
		(pin "C7"
		)
		(pin "C8"
		)
		(pin "C9"
		)
		(pin "D10"
		)
		(pin "D12"
		)
		(pin "D14"
		)
		(pin "D2"
		)
		(pin "D4"
		)
		(pin "D6"
		)
		(pin "D7"
		)
		(pin "D8"
		)
		(pin "D9"
		)
		(pin "E1"
		)
		(pin "E11"
		)
		(pin "E13"
		)
		(pin "E15"
		)
		(pin "E3"
		)
		(pin "E5"
		)
		(pin "E7"
		)
		(pin "E8"
		)
		(pin "E9"
		)
		(pin "F1"
		)
		(pin "F10"
		)
		(pin "F12"
		)
		(pin "F13"
		)
		(pin "F14"
		)
		(pin "F15"
		)
		(pin "F2"
		)
		(pin "F3"
		)
		(pin "F4"
		)
		(pin "F6"
		)
		(pin "F7"
		)
		(pin "F8"
		)
		(pin "F9"
		)
		(pin "G1"
		)
		(pin "G11"
		)
		(pin "G13"
		)
		(pin "G14"
		)
		(pin "G15"
		)
		(pin "G2"
		)
		(pin "G3"
		)
		(pin "G5"
		)
		(pin "G7"
		)
		(pin "G9"
		)
		(pin "H1"
		)
		(pin "H10"
		)
		(pin "H12"
		)
		(pin "H14"
		)
		(pin "H15"
		)
		(pin "H2"
		)
		(pin "H3"
		)
		(pin "H4"
		)
		(pin "H6"
		)
		(pin "H8"
		)
		(pin "J1"
		)
		(pin "J10"
		)
		(pin "J11"
		)
		(pin "J12"
		)
		(pin "J13"
		)
		(pin "J14"
		)
		(pin "J15"
		)
		(pin "J2"
		)
		(pin "J3"
		)
		(pin "J4"
		)
		(pin "J5"
		)
		(pin "J6"
		)
		(pin "J7"
		)
		(pin "J8"
		)
		(pin "K1"
		)
		(pin "K10"
		)
		(pin "K11"
		)
		(pin "K12"
		)
		(pin "K13"
		)
		(pin "K14"
		)
		(pin "K15"
		)
		(pin "K2"
		)
		(pin "K3"
		)
		(pin "K4"
		)
		(pin "K5"
		)
		(pin "K6"
		)
		(pin "K7"
		)
		(pin "K8"
		)
		(pin "K9"
		)
		(pin "L1"
		)
		(pin "L10"
		)
		(pin "L11"
		)
		(pin "L12"
		)
		(pin "L13"
		)
		(pin "L14"
		)
		(pin "L15"
		)
		(pin "L2"
		)
		(pin "L3"
		)
		(pin "L4"
		)
		(pin "L5"
		)
		(pin "L6"
		)
		(pin "L7"
		)
		(pin "L8"
		)
		(pin "L9"
		)
		(pin "M1"
		)
		(pin "M10"
		)
		(pin "M11"
		)
		(pin "M12"
		)
		(pin "M13"
		)
		(pin "M14"
		)
		(pin "M15"
		)
		(pin "M2"
		)
		(pin "M3"
		)
		(pin "M4"
		)
		(pin "M5"
		)
		(pin "M6"
		)
		(pin "M7"
		)
		(pin "M8"
		)
		(pin "M9"
		)
		(pin "N1"
		)
		(pin "N10"
		)
		(pin "N11"
		)
		(pin "N12"
		)
		(pin "N13"
		)
		(pin "N14"
		)
		(pin "N15"
		)
		(pin "N2"
		)
		(pin "N3"
		)
		(pin "N4"
		)
		(pin "N5"
		)
		(pin "N6"
		)
		(pin "N8"
		)
		(pin "N9"
		)
		(pin "P1"
		)
		(pin "P10"
		)
		(pin "P12"
		)
		(pin "P13"
		)
		(pin "P14"
		)
		(pin "P15"
		)
		(pin "P2"
		)
		(pin "P4"
		)
		(pin "P6"
		)
		(pin "P8"
		)
		(pin "R1"
		)
		(pin "R11"
		)
		(pin "R13"
		)
		(pin "R14"
		)
		(pin "R15"
		)
		(pin "R2"
		)
		(pin "R3"
		)
		(pin "R5"
		)
		(pin "R7"
		)
		(pin "R9"
		)
		(pin "T1"
		)
		(pin "T10"
		)
		(pin "T12"
		)
		(pin "T13"
		)
		(pin "T14"
		)
		(pin "T15"
		)
		(pin "T2"
		)
		(pin "T3"
		)
		(pin "T4"
		)
		(pin "T6"
		)
		(pin "T7"
		)
		(pin "T8"
		)
		(pin "T9"
		)
		(pin "U1"
		)
		(pin "U11"
		)
		(pin "U13"
		)
		(pin "U15"
		)
		(pin "U3"
		)
		(pin "U5"
		)
		(pin "U7"
		)
		(pin "U8"
		)
		(pin "U9"
		)
		(pin "V10"
		)
		(pin "V12"
		)
		(pin "V14"
		)
		(pin "V2"
		)
		(pin "V4"
		)
		(pin "V6"
		)
		(pin "V7"
		)
		(pin "V8"
		)
		(pin "V9"
		)
		(pin "W1"
		)
		(pin "W11"
		)
		(pin "W13"
		)
		(pin "W15"
		)
		(pin "W3"
		)
		(pin "W5"
		)
		(pin "W7"
		)
		(pin "W8"
		)
		(pin "W9"
		)
		(pin "Y1"
		)
		(pin "Y10"
		)
		(pin "Y12"
		)
		(pin "Y14"
		)
		(pin "Y15"
		)
		(pin "Y2"
		)
		(pin "Y4"
		)
		(pin "Y6"
		)
		(pin "Y7"
		)
		(pin "Y8"
		)
		(pin "Y9"
		)
		(pin "A12"
		)
		(pin "A4"
		)
		(pin "B11"
		)
		(pin "B13"
		)
		(pin "B3"
		)
		(pin "B5"
		)
		(pin "C10"
		)
		(pin "C12"
		)
		(pin "C14"
		)
		(pin "C2"
		)
		(pin "C4"
		)
		(pin "C6"
		)
		(pin "D1"
		)
		(pin "D11"
		)
		(pin "D13"
		)
		(pin "D15"
		)
		(pin "D3"
		)
		(pin "D5"
		)
		(pin "E10"
		)
		(pin "E12"
		)
		(pin "E14"
		)
		(pin "E2"
		)
		(pin "E4"
		)
		(pin "E6"
		)
		(pin "F11"
		)
		(pin "F5"
		)
		(pin "G10"
		)
		(pin "G12"
		)
		(pin "G4"
		)
		(pin "G6"
		)
		(pin "G8"
		)
		(pin "H11"
		)
		(pin "H13"
		)
		(pin "H5"
		)
		(pin "H7"
		)
		(pin "H9"
		)
		(pin "J9"
		)
		(pin "AA12"
		)
		(pin "AA4"
		)
		(pin "N7"
		)
		(pin "P11"
		)
		(pin "P3"
		)
		(pin "P5"
		)
		(pin "P7"
		)
		(pin "P9"
		)
		(pin "R10"
		)
		(pin "R12"
		)
		(pin "R4"
		)
		(pin "R6"
		)
		(pin "R8"
		)
		(pin "T11"
		)
		(pin "T5"
		)
		(pin "U10"
		)
		(pin "U12"
		)
		(pin "U14"
		)
		(pin "U2"
		)
		(pin "U4"
		)
		(pin "U6"
		)
		(pin "V1"
		)
		(pin "V11"
		)
		(pin "V13"
		)
		(pin "V15"
		)
		(pin "V3"
		)
		(pin "V5"
		)
		(pin "W10"
		)
		(pin "W12"
		)
		(pin "W14"
		)
		(pin "W2"
		)
		(pin "W4"
		)
		(pin "W6"
		)
		(pin "Y11"
		)
		(pin "Y13"
		)
		(pin "Y3"
		)
		(pin "Y5"
		)
		(instances
			(project ""
				(path ""
					(reference "U1")
					(unit 2)
				)
			)
		)
	)
	(symbol
		(lib_id "antmicropower:GND")
		(at 140.97 57.15 0)
		(unit 1)
		(exclude_from_sim no)
		(in_bom yes)
		(on_board yes)
		(dnp no)
		(property "Reference" "#PWR0173"
			(at 140.97 63.5 0)
			(effects
				(font
					(size 1.27 1.27)
				)
				(hide yes)
			)
		)
		(property "Value" "GND"
			(at 140.97 60.96 0)
			(effects
				(font
					(size 1.27 1.27)
				)
			)
		)
		(property "Footprint" ""
			(at 140.97 57.15 0)
			(effects
				(font
					(size 1.27 1.27)
				)
				(hide yes)
			)
		)
		(property "Datasheet" ""
			(at 140.97 57.15 0)
			(effects
				(font
					(size 1.27 1.27)
				)
				(hide yes)
			)
		)
		(property "Description" ""
			(at 140.97 57.15 0)
			(effects
				(font
					(size 1.27 1.27)
				)
			)
		)
		(pin "1"
		)
		(instances
			(project ""
				(path ""
					(reference "#PWR0173")
					(unit 1)
				)
			)
		)
	)
	(symbol
		(lib_id "antmicropower:GND")
		(at 114.3 73.66 0)
		(unit 1)
		(exclude_from_sim no)
		(in_bom yes)
		(on_board yes)
		(dnp no)
		(property "Reference" "#PWR0177"
			(at 114.3 80.01 0)
			(effects
				(font
					(size 1.27 1.27)
				)
				(hide yes)
			)
		)
		(property "Value" "GND"
			(at 114.3 77.47 0)
			(effects
				(font
					(size 1.27 1.27)
				)
			)
		)
		(property "Footprint" ""
			(at 114.3 73.66 0)
			(effects
				(font
					(size 1.27 1.27)
				)
				(hide yes)
			)
		)
		(property "Datasheet" ""
			(at 114.3 73.66 0)
			(effects
				(font
					(size 1.27 1.27)
				)
				(hide yes)
			)
		)
		(property "Description" ""
			(at 114.3 73.66 0)
			(effects
				(font
					(size 1.27 1.27)
				)
			)
		)
		(pin "1"
		)
		(instances
			(project ""
				(path ""
					(reference "#PWR0177")
					(unit 1)
				)
			)
		)
	)
	(symbol
		(lib_id "antmicropower:GND")
		(at 265.43 54.61 0)
		(mirror y)
		(unit 1)
		(exclude_from_sim no)
		(in_bom yes)
		(on_board yes)
		(dnp no)
		(property "Reference" "#PWR0202"
			(at 265.43 60.96 0)
			(effects
				(font
					(size 1.27 1.27)
				)
				(hide yes)
			)
		)
		(property "Value" "GND"
			(at 265.43 58.42 0)
			(effects
				(font
					(size 1.27 1.27)
				)
			)
		)
		(property "Footprint" ""
			(at 265.43 54.61 0)
			(effects
				(font
					(size 1.27 1.27)
				)
				(hide yes)
			)
		)
		(property "Datasheet" ""
			(at 265.43 54.61 0)
			(effects
				(font
					(size 1.27 1.27)
				)
				(hide yes)
			)
		)
		(property "Description" ""
			(at 265.43 54.61 0)
			(effects
				(font
					(size 1.27 1.27)
				)
			)
		)
		(pin "1"
		)
		(instances
			(project ""
				(path ""
					(reference "#PWR0202")
					(unit 1)
				)
			)
		)
	)
	(symbol
		(lib_id "antmicropower:GND")
		(at 238.76 73.66 0)
		(unit 1)
		(exclude_from_sim no)
		(in_bom yes)
		(on_board yes)
		(dnp no)
		(property "Reference" "#PWR0187"
			(at 238.76 80.01 0)
			(effects
				(font
					(size 1.27 1.27)
				)
				(hide yes)
			)
		)
		(property "Value" "GND"
			(at 238.76 77.47 0)
			(effects
				(font
					(size 1.27 1.27)
				)
			)
		)
		(property "Footprint" ""
			(at 238.76 73.66 0)
			(effects
				(font
					(size 1.27 1.27)
				)
				(hide yes)
			)
		)
		(property "Datasheet" ""
			(at 238.76 73.66 0)
			(effects
				(font
					(size 1.27 1.27)
				)
				(hide yes)
			)
		)
		(property "Description" ""
			(at 238.76 73.66 0)
			(effects
				(font
					(size 1.27 1.27)
				)
			)
		)
		(pin "1"
		)
		(instances
			(project ""
				(path ""
					(reference "#PWR0187")
					(unit 1)
				)
			)
		)
	)
	(symbol
		(lib_id "antmicroCapacitors0402:C_4u7_0402")
		(at 229.87 73.66 90)
		(unit 1)
		(exclude_from_sim no)
		(in_bom yes)
		(on_board yes)
		(dnp no)
		(fields_autoplaced yes)
		(property "Reference" "C51"
			(at 232.41 69.8435 90)
			(effects
				(font
					(size 1.27 1.27)
					(thickness 0.15)
				)
				(justify right)
			)
		)
		(property "Value" "C_4u7_0402"
			(at 240.03 53.34 0)
			(effects
				(font
					(size 1.27 1.27)
					(thickness 0.15)
				)
				(justify left bottom)
				(hide yes)
			)
		)
		(property "Footprint" "antmicro-footprints:C_0402_1005Metric"
			(at 242.57 53.34 0)
			(effects
				(font
					(size 1.27 1.27)
					(thickness 0.15)
				)
				(justify left bottom)
				(hide yes)
			)
		)
		(property "Datasheet" "https://www.murata.com/products/productdetail?partno=GRM155R61A475MEAA%23"
			(at 245.11 53.34 0)
			(effects
				(font
					(size 1.27 1.27)
					(thickness 0.15)
				)
				(justify left bottom)
				(hide yes)
			)
		)
		(property "Description" ""
			(at 229.87 73.66 0)
			(effects
				(font
					(size 1.27 1.27)
				)
			)
		)
		(property "MPN" "GRM155R61A475MEAAD"
			(at 247.65 53.34 0)
			(effects
				(font
					(size 1.27 1.27)
					(thickness 0.15)
				)
				(justify left bottom)
				(hide yes)
			)
		)
		(property "Manufacturer" "Murata"
			(at 250.19 53.34 0)
			(effects
				(font
					(size 1.27 1.27)
					(thickness 0.15)
				)
				(justify left bottom)
				(hide yes)
			)
		)
		(property "License" "Apache-2.0"
			(at 252.73 53.34 0)
			(effects
				(font
					(size 1.27 1.27)
					(thickness 0.15)
				)
				(justify left bottom)
				(hide yes)
			)
		)
		(property "Author" "Antmicro"
			(at 255.27 53.34 0)
			(effects
				(font
					(size 1.27 1.27)
					(thickness 0.15)
				)
				(justify left bottom)
				(hide yes)
			)
		)
		(property "Val" "4u7"
			(at 232.41 72.3835 90)
			(effects
				(font
					(size 1.27 1.27)
					(thickness 0.15)
				)
				(justify right)
			)
		)
		(property "Voltage" ""
			(at 257.81 53.34 0)
			(effects
				(font
					(size 1.27 1.27)
				)
				(justify left bottom)
				(hide yes)
			)
		)
		(property "Dielectric" ""
			(at 260.35 53.34 0)
			(effects
				(font
					(size 1.27 1.27)
				)
				(justify left bottom)
				(hide yes)
			)
		)
		(pin "1"
		)
		(pin "2"
		)
		(instances
			(project ""
				(path ""
					(reference "C51")
					(unit 1)
				)
			)
		)
	)
	(symbol
		(lib_id "antmicroCapacitors0402:C_4u7_0402")
		(at 247.65 73.66 90)
		(unit 1)
		(exclude_from_sim no)
		(in_bom yes)
		(on_board yes)
		(dnp no)
		(fields_autoplaced yes)
		(property "Reference" "C59"
			(at 250.19 69.8435 90)
			(effects
				(font
					(size 1.27 1.27)
					(thickness 0.15)
				)
				(justify right)
			)
		)
		(property "Value" "C_4u7_0402"
			(at 257.81 53.34 0)
			(effects
				(font
					(size 1.27 1.27)
					(thickness 0.15)
				)
				(justify left bottom)
				(hide yes)
			)
		)
		(property "Footprint" "antmicro-footprints:C_0402_1005Metric"
			(at 260.35 53.34 0)
			(effects
				(font
					(size 1.27 1.27)
					(thickness 0.15)
				)
				(justify left bottom)
				(hide yes)
			)
		)
		(property "Datasheet" "https://www.murata.com/products/productdetail?partno=GRM155R61A475MEAA%23"
			(at 262.89 53.34 0)
			(effects
				(font
					(size 1.27 1.27)
					(thickness 0.15)
				)
				(justify left bottom)
				(hide yes)
			)
		)
		(property "Description" ""
			(at 247.65 73.66 0)
			(effects
				(font
					(size 1.27 1.27)
				)
			)
		)
		(property "MPN" "GRM155R61A475MEAAD"
			(at 265.43 53.34 0)
			(effects
				(font
					(size 1.27 1.27)
					(thickness 0.15)
				)
				(justify left bottom)
				(hide yes)
			)
		)
		(property "Manufacturer" "Murata"
			(at 267.97 53.34 0)
			(effects
				(font
					(size 1.27 1.27)
					(thickness 0.15)
				)
				(justify left bottom)
				(hide yes)
			)
		)
		(property "License" "Apache-2.0"
			(at 270.51 53.34 0)
			(effects
				(font
					(size 1.27 1.27)
					(thickness 0.15)
				)
				(justify left bottom)
				(hide yes)
			)
		)
		(property "Author" "Antmicro"
			(at 273.05 53.34 0)
			(effects
				(font
					(size 1.27 1.27)
					(thickness 0.15)
				)
				(justify left bottom)
				(hide yes)
			)
		)
		(property "Val" "4u7"
			(at 250.19 72.3835 90)
			(effects
				(font
					(size 1.27 1.27)
					(thickness 0.15)
				)
				(justify right)
			)
		)
		(property "Voltage" ""
			(at 275.59 53.34 0)
			(effects
				(font
					(size 1.27 1.27)
				)
				(justify left bottom)
				(hide yes)
			)
		)
		(property "Dielectric" ""
			(at 278.13 53.34 0)
			(effects
				(font
					(size 1.27 1.27)
				)
				(justify left bottom)
				(hide yes)
			)
		)
		(pin "1"
		)
		(pin "2"
		)
		(instances
			(project ""
				(path ""
					(reference "C59")
					(unit 1)
				)
			)
		)
	)
	(symbol
		(lib_id "antmicroResistors0402:R_240R_0402")
		(at 170.18 82.55 90)
		(unit 1)
		(exclude_from_sim no)
		(in_bom yes)
		(on_board yes)
		(dnp no)
		(property "Reference" "R69"
			(at 171.45 78.74 90)
			(effects
				(font
					(size 1.27 1.27)
					(thickness 0.15)
				)
				(justify right)
			)
		)
		(property "Value" "R_240R_0402"
			(at 182.88 62.23 0)
			(effects
				(font
					(size 1.27 1.27)
					(thickness 0.15)
				)
				(justify left bottom)
				(hide yes)
			)
		)
		(property "Footprint" "antmicro-footprints:R_0402_1005Metric"
			(at 185.42 62.23 0)
			(effects
				(font
					(size 1.27 1.27)
					(thickness 0.15)
				)
				(justify left bottom)
				(hide yes)
			)
		)
		(property "Datasheet" "https://www.bourns.com/docs/product-datasheets/cr.pdf"
			(at 187.96 62.23 0)
			(effects
				(font
					(size 1.27 1.27)
					(thickness 0.15)
				)
				(justify left bottom)
				(hide yes)
			)
		)
		(property "Description" ""
			(at 170.18 82.55 0)
			(effects
				(font
					(size 1.27 1.27)
				)
			)
		)
		(property "MPN" "CR0402-FX-2400GLF"
			(at 190.5 62.23 0)
			(effects
				(font
					(size 1.27 1.27)
					(thickness 0.15)
				)
				(justify left bottom)
				(hide yes)
			)
		)
		(property "Manufacturer" "Bourns"
			(at 193.04 62.23 0)
			(effects
				(font
					(size 1.27 1.27)
					(thickness 0.15)
				)
				(justify left bottom)
				(hide yes)
			)
		)
		(property "License" "Apache-2.0"
			(at 195.58 62.23 0)
			(effects
				(font
					(size 1.27 1.27)
					(thickness 0.15)
				)
				(justify left bottom)
				(hide yes)
			)
		)
		(property "Author" "Antmicro"
			(at 198.12 62.23 0)
			(effects
				(font
					(size 1.27 1.27)
					(thickness 0.15)
				)
				(justify left bottom)
				(hide yes)
			)
		)
		(property "Val" "240R"
			(at 171.45 81.28 90)
			(effects
				(font
					(size 1.27 1.27)
					(thickness 0.15)
				)
				(justify right)
			)
		)
		(property "Tolerance" "1%"
			(at 180.34 62.23 0)
			(effects
				(font
					(size 1.27 1.27)
				)
				(justify left bottom)
				(hide yes)
			)
		)
		(pin "1"
		)
		(pin "2"
		)
		(instances
			(project ""
				(path ""
					(reference "R69")
					(unit 1)
				)
			)
		)
	)
	(symbol
		(lib_id "antmicropower:GND")
		(at 229.87 73.66 0)
		(unit 1)
		(exclude_from_sim no)
		(in_bom yes)
		(on_board yes)
		(dnp no)
		(property "Reference" "#PWR0195"
			(at 229.87 80.01 0)
			(effects
				(font
					(size 1.27 1.27)
				)
				(hide yes)
			)
		)
		(property "Value" "GND"
			(at 229.87 77.47 0)
			(effects
				(font
					(size 1.27 1.27)
				)
			)
		)
		(property "Footprint" ""
			(at 229.87 73.66 0)
			(effects
				(font
					(size 1.27 1.27)
				)
				(hide yes)
			)
		)
		(property "Datasheet" ""
			(at 229.87 73.66 0)
			(effects
				(font
					(size 1.27 1.27)
				)
				(hide yes)
			)
		)
		(property "Description" ""
			(at 229.87 73.66 0)
			(effects
				(font
					(size 1.27 1.27)
				)
			)
		)
		(pin "1"
		)
		(instances
			(project ""
				(path ""
					(reference "#PWR0195")
					(unit 1)
				)
			)
		)
	)
	(symbol
		(lib_id "antmicroCapacitors0402:C_4u7_0402")
		(at 114.3 87.63 90)
		(unit 1)
		(exclude_from_sim no)
		(in_bom yes)
		(on_board yes)
		(dnp no)
		(fields_autoplaced yes)
		(property "Reference" "C40"
			(at 116.84 83.8135 90)
			(effects
				(font
					(size 1.27 1.27)
					(thickness 0.15)
				)
				(justify right)
			)
		)
		(property "Value" "C_4u7_0402"
			(at 124.46 67.31 0)
			(effects
				(font
					(size 1.27 1.27)
					(thickness 0.15)
				)
				(justify left bottom)
				(hide yes)
			)
		)
		(property "Footprint" "antmicro-footprints:C_0402_1005Metric"
			(at 127 67.31 0)
			(effects
				(font
					(size 1.27 1.27)
					(thickness 0.15)
				)
				(justify left bottom)
				(hide yes)
			)
		)
		(property "Datasheet" "https://www.murata.com/products/productdetail?partno=GRM155R61A475MEAA%23"
			(at 129.54 67.31 0)
			(effects
				(font
					(size 1.27 1.27)
					(thickness 0.15)
				)
				(justify left bottom)
				(hide yes)
			)
		)
		(property "Description" ""
			(at 114.3 87.63 0)
			(effects
				(font
					(size 1.27 1.27)
				)
			)
		)
		(property "MPN" "GRM155R61A475MEAAD"
			(at 132.08 67.31 0)
			(effects
				(font
					(size 1.27 1.27)
					(thickness 0.15)
				)
				(justify left bottom)
				(hide yes)
			)
		)
		(property "Manufacturer" "Murata"
			(at 134.62 67.31 0)
			(effects
				(font
					(size 1.27 1.27)
					(thickness 0.15)
				)
				(justify left bottom)
				(hide yes)
			)
		)
		(property "License" "Apache-2.0"
			(at 137.16 67.31 0)
			(effects
				(font
					(size 1.27 1.27)
					(thickness 0.15)
				)
				(justify left bottom)
				(hide yes)
			)
		)
		(property "Author" "Antmicro"
			(at 139.7 67.31 0)
			(effects
				(font
					(size 1.27 1.27)
					(thickness 0.15)
				)
				(justify left bottom)
				(hide yes)
			)
		)
		(property "Val" "4u7"
			(at 116.84 86.3535 90)
			(effects
				(font
					(size 1.27 1.27)
					(thickness 0.15)
				)
				(justify right)
			)
		)
		(property "Voltage" ""
			(at 142.24 67.31 0)
			(effects
				(font
					(size 1.27 1.27)
				)
				(justify left bottom)
				(hide yes)
			)
		)
		(property "Dielectric" ""
			(at 144.78 67.31 0)
			(effects
				(font
					(size 1.27 1.27)
				)
				(justify left bottom)
				(hide yes)
			)
		)
		(pin "1"
		)
		(pin "2"
		)
		(instances
			(project ""
				(path ""
					(reference "C40")
					(unit 1)
				)
			)
		)
	)
	(symbol
		(lib_id "antmicropower:GND")
		(at 105.41 73.66 0)
		(unit 1)
		(exclude_from_sim no)
		(in_bom yes)
		(on_board yes)
		(dnp no)
		(property "Reference" "#PWR0174"
			(at 105.41 80.01 0)
			(effects
				(font
					(size 1.27 1.27)
				)
				(hide yes)
			)
		)
		(property "Value" "GND"
			(at 105.41 77.47 0)
			(effects
				(font
					(size 1.27 1.27)
				)
			)
		)
		(property "Footprint" ""
			(at 105.41 73.66 0)
			(effects
				(font
					(size 1.27 1.27)
				)
				(hide yes)
			)
		)
		(property "Datasheet" ""
			(at 105.41 73.66 0)
			(effects
				(font
					(size 1.27 1.27)
				)
				(hide yes)
			)
		)
		(property "Description" ""
			(at 105.41 73.66 0)
			(effects
				(font
					(size 1.27 1.27)
				)
			)
		)
		(pin "1"
		)
		(instances
			(project ""
				(path ""
					(reference "#PWR0174")
					(unit 1)
				)
			)
		)
	)
	(symbol
		(lib_id "antmicropower:GND")
		(at 256.54 40.64 0)
		(mirror y)
		(unit 1)
		(exclude_from_sim no)
		(in_bom yes)
		(on_board yes)
		(dnp no)
		(property "Reference" "#PWR0200"
			(at 256.54 46.99 0)
			(effects
				(font
					(size 1.27 1.27)
				)
				(hide yes)
			)
		)
		(property "Value" "GND"
			(at 256.54 44.45 0)
			(effects
				(font
					(size 1.27 1.27)
				)
			)
		)
		(property "Footprint" ""
			(at 256.54 40.64 0)
			(effects
				(font
					(size 1.27 1.27)
				)
				(hide yes)
			)
		)
		(property "Datasheet" ""
			(at 256.54 40.64 0)
			(effects
				(font
					(size 1.27 1.27)
				)
				(hide yes)
			)
		)
		(property "Description" ""
			(at 256.54 40.64 0)
			(effects
				(font
					(size 1.27 1.27)
				)
			)
		)
		(pin "1"
		)
		(instances
			(project ""
				(path ""
					(reference "#PWR0200")
					(unit 1)
				)
			)
		)
	)
	(symbol
		(lib_id "antmicroCapacitors0402:C_4u7_0402")
		(at 132.08 57.15 90)
		(unit 1)
		(exclude_from_sim no)
		(in_bom yes)
		(on_board yes)
		(dnp no)
		(fields_autoplaced yes)
		(property "Reference" "C38"
			(at 134.62 53.3335 90)
			(effects
				(font
					(size 1.27 1.27)
					(thickness 0.15)
				)
				(justify right)
			)
		)
		(property "Value" "C_4u7_0402"
			(at 142.24 36.83 0)
			(effects
				(font
					(size 1.27 1.27)
					(thickness 0.15)
				)
				(justify left bottom)
				(hide yes)
			)
		)
		(property "Footprint" "antmicro-footprints:C_0402_1005Metric"
			(at 144.78 36.83 0)
			(effects
				(font
					(size 1.27 1.27)
					(thickness 0.15)
				)
				(justify left bottom)
				(hide yes)
			)
		)
		(property "Datasheet" "https://www.murata.com/products/productdetail?partno=GRM155R61A475MEAA%23"
			(at 147.32 36.83 0)
			(effects
				(font
					(size 1.27 1.27)
					(thickness 0.15)
				)
				(justify left bottom)
				(hide yes)
			)
		)
		(property "Description" ""
			(at 132.08 57.15 0)
			(effects
				(font
					(size 1.27 1.27)
				)
			)
		)
		(property "MPN" "GRM155R61A475MEAAD"
			(at 149.86 36.83 0)
			(effects
				(font
					(size 1.27 1.27)
					(thickness 0.15)
				)
				(justify left bottom)
				(hide yes)
			)
		)
		(property "Manufacturer" "Murata"
			(at 152.4 36.83 0)
			(effects
				(font
					(size 1.27 1.27)
					(thickness 0.15)
				)
				(justify left bottom)
				(hide yes)
			)
		)
		(property "License" "Apache-2.0"
			(at 154.94 36.83 0)
			(effects
				(font
					(size 1.27 1.27)
					(thickness 0.15)
				)
				(justify left bottom)
				(hide yes)
			)
		)
		(property "Author" "Antmicro"
			(at 157.48 36.83 0)
			(effects
				(font
					(size 1.27 1.27)
					(thickness 0.15)
				)
				(justify left bottom)
				(hide yes)
			)
		)
		(property "Val" "4u7"
			(at 134.62 55.8735 90)
			(effects
				(font
					(size 1.27 1.27)
					(thickness 0.15)
				)
				(justify right)
			)
		)
		(property "Voltage" ""
			(at 160.02 36.83 0)
			(effects
				(font
					(size 1.27 1.27)
				)
				(justify left bottom)
				(hide yes)
			)
		)
		(property "Dielectric" ""
			(at 162.56 36.83 0)
			(effects
				(font
					(size 1.27 1.27)
				)
				(justify left bottom)
				(hide yes)
			)
		)
		(pin "1"
		)
		(pin "2"
		)
		(instances
			(project ""
				(path ""
					(reference "C38")
					(unit 1)
				)
			)
		)
	)
	(symbol
		(lib_id "antmicroCapacitors0402:C_4u7_0402")
		(at 140.97 87.63 90)
		(unit 1)
		(exclude_from_sim no)
		(in_bom yes)
		(on_board yes)
		(dnp no)
		(fields_autoplaced yes)
		(property "Reference" "C48"
			(at 143.51 83.8135 90)
			(effects
				(font
					(size 1.27 1.27)
					(thickness 0.15)
				)
				(justify right)
			)
		)
		(property "Value" "C_4u7_0402"
			(at 151.13 67.31 0)
			(effects
				(font
					(size 1.27 1.27)
					(thickness 0.15)
				)
				(justify left bottom)
				(hide yes)
			)
		)
		(property "Footprint" "antmicro-footprints:C_0402_1005Metric"
			(at 153.67 67.31 0)
			(effects
				(font
					(size 1.27 1.27)
					(thickness 0.15)
				)
				(justify left bottom)
				(hide yes)
			)
		)
		(property "Datasheet" "https://www.murata.com/products/productdetail?partno=GRM155R61A475MEAA%23"
			(at 156.21 67.31 0)
			(effects
				(font
					(size 1.27 1.27)
					(thickness 0.15)
				)
				(justify left bottom)
				(hide yes)
			)
		)
		(property "Description" ""
			(at 140.97 87.63 0)
			(effects
				(font
					(size 1.27 1.27)
				)
			)
		)
		(property "MPN" "GRM155R61A475MEAAD"
			(at 158.75 67.31 0)
			(effects
				(font
					(size 1.27 1.27)
					(thickness 0.15)
				)
				(justify left bottom)
				(hide yes)
			)
		)
		(property "Manufacturer" "Murata"
			(at 161.29 67.31 0)
			(effects
				(font
					(size 1.27 1.27)
					(thickness 0.15)
				)
				(justify left bottom)
				(hide yes)
			)
		)
		(property "License" "Apache-2.0"
			(at 163.83 67.31 0)
			(effects
				(font
					(size 1.27 1.27)
					(thickness 0.15)
				)
				(justify left bottom)
				(hide yes)
			)
		)
		(property "Author" "Antmicro"
			(at 166.37 67.31 0)
			(effects
				(font
					(size 1.27 1.27)
					(thickness 0.15)
				)
				(justify left bottom)
				(hide yes)
			)
		)
		(property "Val" "4u7"
			(at 143.51 86.3535 90)
			(effects
				(font
					(size 1.27 1.27)
					(thickness 0.15)
				)
				(justify right)
			)
		)
		(property "Voltage" ""
			(at 168.91 67.31 0)
			(effects
				(font
					(size 1.27 1.27)
				)
				(justify left bottom)
				(hide yes)
			)
		)
		(property "Dielectric" ""
			(at 171.45 67.31 0)
			(effects
				(font
					(size 1.27 1.27)
				)
				(justify left bottom)
				(hide yes)
			)
		)
		(pin "1"
		)
		(pin "2"
		)
		(instances
			(project ""
				(path ""
					(reference "C48")
					(unit 1)
				)
			)
		)
	)
	(symbol
		(lib_id "antmicroCapacitors0402:C_4u7_0402")
		(at 114.3 73.66 90)
		(unit 1)
		(exclude_from_sim no)
		(in_bom yes)
		(on_board yes)
		(dnp no)
		(fields_autoplaced yes)
		(property "Reference" "C39"
			(at 116.84 69.8435 90)
			(effects
				(font
					(size 1.27 1.27)
					(thickness 0.15)
				)
				(justify right)
			)
		)
		(property "Value" "C_4u7_0402"
			(at 124.46 53.34 0)
			(effects
				(font
					(size 1.27 1.27)
					(thickness 0.15)
				)
				(justify left bottom)
				(hide yes)
			)
		)
		(property "Footprint" "antmicro-footprints:C_0402_1005Metric"
			(at 127 53.34 0)
			(effects
				(font
					(size 1.27 1.27)
					(thickness 0.15)
				)
				(justify left bottom)
				(hide yes)
			)
		)
		(property "Datasheet" "https://www.murata.com/products/productdetail?partno=GRM155R61A475MEAA%23"
			(at 129.54 53.34 0)
			(effects
				(font
					(size 1.27 1.27)
					(thickness 0.15)
				)
				(justify left bottom)
				(hide yes)
			)
		)
		(property "Description" ""
			(at 114.3 73.66 0)
			(effects
				(font
					(size 1.27 1.27)
				)
			)
		)
		(property "MPN" "GRM155R61A475MEAAD"
			(at 132.08 53.34 0)
			(effects
				(font
					(size 1.27 1.27)
					(thickness 0.15)
				)
				(justify left bottom)
				(hide yes)
			)
		)
		(property "Manufacturer" "Murata"
			(at 134.62 53.34 0)
			(effects
				(font
					(size 1.27 1.27)
					(thickness 0.15)
				)
				(justify left bottom)
				(hide yes)
			)
		)
		(property "License" "Apache-2.0"
			(at 137.16 53.34 0)
			(effects
				(font
					(size 1.27 1.27)
					(thickness 0.15)
				)
				(justify left bottom)
				(hide yes)
			)
		)
		(property "Author" "Antmicro"
			(at 139.7 53.34 0)
			(effects
				(font
					(size 1.27 1.27)
					(thickness 0.15)
				)
				(justify left bottom)
				(hide yes)
			)
		)
		(property "Val" "4u7"
			(at 116.84 72.3835 90)
			(effects
				(font
					(size 1.27 1.27)
					(thickness 0.15)
				)
				(justify right)
			)
		)
		(property "Voltage" ""
			(at 142.24 53.34 0)
			(effects
				(font
					(size 1.27 1.27)
				)
				(justify left bottom)
				(hide yes)
			)
		)
		(property "Dielectric" ""
			(at 144.78 53.34 0)
			(effects
				(font
					(size 1.27 1.27)
				)
				(justify left bottom)
				(hide yes)
			)
		)
		(pin "1"
		)
		(pin "2"
		)
		(instances
			(project ""
				(path ""
					(reference "C39")
					(unit 1)
				)
			)
		)
	)
	(symbol
		(lib_id "antmicroCapacitors0402:C_4u7_0402")
		(at 105.41 87.63 90)
		(unit 1)
		(exclude_from_sim no)
		(in_bom yes)
		(on_board yes)
		(dnp no)
		(fields_autoplaced yes)
		(property "Reference" "C37"
			(at 107.95 83.8135 90)
			(effects
				(font
					(size 1.27 1.27)
					(thickness 0.15)
				)
				(justify right)
			)
		)
		(property "Value" "C_4u7_0402"
			(at 115.57 67.31 0)
			(effects
				(font
					(size 1.27 1.27)
					(thickness 0.15)
				)
				(justify left bottom)
				(hide yes)
			)
		)
		(property "Footprint" "antmicro-footprints:C_0402_1005Metric"
			(at 118.11 67.31 0)
			(effects
				(font
					(size 1.27 1.27)
					(thickness 0.15)
				)
				(justify left bottom)
				(hide yes)
			)
		)
		(property "Datasheet" "https://www.murata.com/products/productdetail?partno=GRM155R61A475MEAA%23"
			(at 120.65 67.31 0)
			(effects
				(font
					(size 1.27 1.27)
					(thickness 0.15)
				)
				(justify left bottom)
				(hide yes)
			)
		)
		(property "Description" ""
			(at 105.41 87.63 0)
			(effects
				(font
					(size 1.27 1.27)
				)
			)
		)
		(property "MPN" "GRM155R61A475MEAAD"
			(at 123.19 67.31 0)
			(effects
				(font
					(size 1.27 1.27)
					(thickness 0.15)
				)
				(justify left bottom)
				(hide yes)
			)
		)
		(property "Manufacturer" "Murata"
			(at 125.73 67.31 0)
			(effects
				(font
					(size 1.27 1.27)
					(thickness 0.15)
				)
				(justify left bottom)
				(hide yes)
			)
		)
		(property "License" "Apache-2.0"
			(at 128.27 67.31 0)
			(effects
				(font
					(size 1.27 1.27)
					(thickness 0.15)
				)
				(justify left bottom)
				(hide yes)
			)
		)
		(property "Author" "Antmicro"
			(at 130.81 67.31 0)
			(effects
				(font
					(size 1.27 1.27)
					(thickness 0.15)
				)
				(justify left bottom)
				(hide yes)
			)
		)
		(property "Val" "4u7"
			(at 107.95 86.3535 90)
			(effects
				(font
					(size 1.27 1.27)
					(thickness 0.15)
				)
				(justify right)
			)
		)
		(property "Voltage" ""
			(at 133.35 67.31 0)
			(effects
				(font
					(size 1.27 1.27)
				)
				(justify left bottom)
				(hide yes)
			)
		)
		(property "Dielectric" ""
			(at 135.89 67.31 0)
			(effects
				(font
					(size 1.27 1.27)
				)
				(justify left bottom)
				(hide yes)
			)
		)
		(pin "1"
		)
		(pin "2"
		)
		(instances
			(project ""
				(path ""
					(reference "C37")
					(unit 1)
				)
			)
		)
	)
	(symbol
		(lib_id "antmicropower:GND")
		(at 238.76 54.61 0)
		(mirror y)
		(unit 1)
		(exclude_from_sim no)
		(in_bom yes)
		(on_board yes)
		(dnp no)
		(property "Reference" "#PWR0179"
			(at 238.76 60.96 0)
			(effects
				(font
					(size 1.27 1.27)
				)
				(hide yes)
			)
		)
		(property "Value" "GND"
			(at 238.76 58.42 0)
			(effects
				(font
					(size 1.27 1.27)
				)
			)
		)
		(property "Footprint" ""
			(at 238.76 54.61 0)
			(effects
				(font
					(size 1.27 1.27)
				)
				(hide yes)
			)
		)
		(property "Datasheet" ""
			(at 238.76 54.61 0)
			(effects
				(font
					(size 1.27 1.27)
				)
				(hide yes)
			)
		)
		(property "Description" ""
			(at 238.76 54.61 0)
			(effects
				(font
					(size 1.27 1.27)
				)
			)
		)
		(pin "1"
		)
		(instances
			(project ""
				(path ""
					(reference "#PWR0179")
					(unit 1)
				)
			)
		)
	)
	(symbol
		(lib_id "antmicroCapacitors0402:C_4u7_0402")
		(at 132.08 73.66 90)
		(unit 1)
		(exclude_from_sim no)
		(in_bom yes)
		(on_board yes)
		(dnp no)
		(fields_autoplaced yes)
		(property "Reference" "C45"
			(at 134.62 69.8435 90)
			(effects
				(font
					(size 1.27 1.27)
					(thickness 0.15)
				)
				(justify right)
			)
		)
		(property "Value" "C_4u7_0402"
			(at 142.24 53.34 0)
			(effects
				(font
					(size 1.27 1.27)
					(thickness 0.15)
				)
				(justify left bottom)
				(hide yes)
			)
		)
		(property "Footprint" "antmicro-footprints:C_0402_1005Metric"
			(at 144.78 53.34 0)
			(effects
				(font
					(size 1.27 1.27)
					(thickness 0.15)
				)
				(justify left bottom)
				(hide yes)
			)
		)
		(property "Datasheet" "https://www.murata.com/products/productdetail?partno=GRM155R61A475MEAA%23"
			(at 147.32 53.34 0)
			(effects
				(font
					(size 1.27 1.27)
					(thickness 0.15)
				)
				(justify left bottom)
				(hide yes)
			)
		)
		(property "Description" ""
			(at 132.08 73.66 0)
			(effects
				(font
					(size 1.27 1.27)
				)
			)
		)
		(property "MPN" "GRM155R61A475MEAAD"
			(at 149.86 53.34 0)
			(effects
				(font
					(size 1.27 1.27)
					(thickness 0.15)
				)
				(justify left bottom)
				(hide yes)
			)
		)
		(property "Manufacturer" "Murata"
			(at 152.4 53.34 0)
			(effects
				(font
					(size 1.27 1.27)
					(thickness 0.15)
				)
				(justify left bottom)
				(hide yes)
			)
		)
		(property "License" "Apache-2.0"
			(at 154.94 53.34 0)
			(effects
				(font
					(size 1.27 1.27)
					(thickness 0.15)
				)
				(justify left bottom)
				(hide yes)
			)
		)
		(property "Author" "Antmicro"
			(at 157.48 53.34 0)
			(effects
				(font
					(size 1.27 1.27)
					(thickness 0.15)
				)
				(justify left bottom)
				(hide yes)
			)
		)
		(property "Val" "4u7"
			(at 134.62 72.3835 90)
			(effects
				(font
					(size 1.27 1.27)
					(thickness 0.15)
				)
				(justify right)
			)
		)
		(property "Voltage" ""
			(at 160.02 53.34 0)
			(effects
				(font
					(size 1.27 1.27)
				)
				(justify left bottom)
				(hide yes)
			)
		)
		(property "Dielectric" ""
			(at 162.56 53.34 0)
			(effects
				(font
					(size 1.27 1.27)
				)
				(justify left bottom)
				(hide yes)
			)
		)
		(pin "1"
		)
		(pin "2"
		)
		(instances
			(project ""
				(path ""
					(reference "C45")
					(unit 1)
				)
			)
		)
	)
	(symbol
		(lib_id "antmicropower:GND")
		(at 177.8 83.82 0)
		(unit 1)
		(exclude_from_sim no)
		(in_bom yes)
		(on_board yes)
		(dnp no)
		(property "Reference" "#PWR0105"
			(at 177.8 90.17 0)
			(effects
				(font
					(size 1.27 1.27)
				)
				(hide yes)
			)
		)
		(property "Value" "GND"
			(at 177.927 88.2142 0)
			(effects
				(font
					(size 1.27 1.27)
				)
			)
		)
		(property "Footprint" ""
			(at 177.8 83.82 0)
			(effects
				(font
					(size 1.27 1.27)
				)
				(hide yes)
			)
		)
		(property "Datasheet" ""
			(at 177.8 83.82 0)
			(effects
				(font
					(size 1.27 1.27)
				)
				(hide yes)
			)
		)
		(property "Description" ""
			(at 177.8 83.82 0)
			(effects
				(font
					(size 1.27 1.27)
				)
			)
		)
		(pin "1"
		)
		(instances
			(project ""
				(path ""
					(reference "#PWR0105")
					(unit 1)
				)
			)
		)
	)
	(symbol
		(lib_id "antmicroCapacitors0402:C_4u7_0402")
		(at 229.87 87.63 90)
		(unit 1)
		(exclude_from_sim no)
		(in_bom yes)
		(on_board yes)
		(dnp no)
		(fields_autoplaced yes)
		(property "Reference" "C52"
			(at 232.41 83.8135 90)
			(effects
				(font
					(size 1.27 1.27)
					(thickness 0.15)
				)
				(justify right)
			)
		)
		(property "Value" "C_4u7_0402"
			(at 240.03 67.31 0)
			(effects
				(font
					(size 1.27 1.27)
					(thickness 0.15)
				)
				(justify left bottom)
				(hide yes)
			)
		)
		(property "Footprint" "antmicro-footprints:C_0402_1005Metric"
			(at 242.57 67.31 0)
			(effects
				(font
					(size 1.27 1.27)
					(thickness 0.15)
				)
				(justify left bottom)
				(hide yes)
			)
		)
		(property "Datasheet" "https://www.murata.com/products/productdetail?partno=GRM155R61A475MEAA%23"
			(at 245.11 67.31 0)
			(effects
				(font
					(size 1.27 1.27)
					(thickness 0.15)
				)
				(justify left bottom)
				(hide yes)
			)
		)
		(property "Description" ""
			(at 229.87 87.63 0)
			(effects
				(font
					(size 1.27 1.27)
				)
			)
		)
		(property "MPN" "GRM155R61A475MEAAD"
			(at 247.65 67.31 0)
			(effects
				(font
					(size 1.27 1.27)
					(thickness 0.15)
				)
				(justify left bottom)
				(hide yes)
			)
		)
		(property "Manufacturer" "Murata"
			(at 250.19 67.31 0)
			(effects
				(font
					(size 1.27 1.27)
					(thickness 0.15)
				)
				(justify left bottom)
				(hide yes)
			)
		)
		(property "License" "Apache-2.0"
			(at 252.73 67.31 0)
			(effects
				(font
					(size 1.27 1.27)
					(thickness 0.15)
				)
				(justify left bottom)
				(hide yes)
			)
		)
		(property "Author" "Antmicro"
			(at 255.27 67.31 0)
			(effects
				(font
					(size 1.27 1.27)
					(thickness 0.15)
				)
				(justify left bottom)
				(hide yes)
			)
		)
		(property "Val" "4u7"
			(at 232.41 86.3535 90)
			(effects
				(font
					(size 1.27 1.27)
					(thickness 0.15)
				)
				(justify right)
			)
		)
		(property "Voltage" ""
			(at 257.81 67.31 0)
			(effects
				(font
					(size 1.27 1.27)
				)
				(justify left bottom)
				(hide yes)
			)
		)
		(property "Dielectric" ""
			(at 260.35 67.31 0)
			(effects
				(font
					(size 1.27 1.27)
				)
				(justify left bottom)
				(hide yes)
			)
		)
		(pin "1"
		)
		(pin "2"
		)
		(instances
			(project ""
				(path ""
					(reference "C52")
					(unit 1)
				)
			)
		)
	)
	(symbol
		(lib_id "antmicroCapacitors0402:C_4u7_0402")
		(at 140.97 57.15 90)
		(unit 1)
		(exclude_from_sim no)
		(in_bom yes)
		(on_board yes)
		(dnp no)
		(fields_autoplaced yes)
		(property "Reference" "C41"
			(at 143.51 53.3335 90)
			(effects
				(font
					(size 1.27 1.27)
					(thickness 0.15)
				)
				(justify right)
			)
		)
		(property "Value" "C_4u7_0402"
			(at 151.13 36.83 0)
			(effects
				(font
					(size 1.27 1.27)
					(thickness 0.15)
				)
				(justify left bottom)
				(hide yes)
			)
		)
		(property "Footprint" "antmicro-footprints:C_0402_1005Metric"
			(at 153.67 36.83 0)
			(effects
				(font
					(size 1.27 1.27)
					(thickness 0.15)
				)
				(justify left bottom)
				(hide yes)
			)
		)
		(property "Datasheet" "https://www.murata.com/products/productdetail?partno=GRM155R61A475MEAA%23"
			(at 156.21 36.83 0)
			(effects
				(font
					(size 1.27 1.27)
					(thickness 0.15)
				)
				(justify left bottom)
				(hide yes)
			)
		)
		(property "Description" ""
			(at 140.97 57.15 0)
			(effects
				(font
					(size 1.27 1.27)
				)
			)
		)
		(property "MPN" "GRM155R61A475MEAAD"
			(at 158.75 36.83 0)
			(effects
				(font
					(size 1.27 1.27)
					(thickness 0.15)
				)
				(justify left bottom)
				(hide yes)
			)
		)
		(property "Manufacturer" "Murata"
			(at 161.29 36.83 0)
			(effects
				(font
					(size 1.27 1.27)
					(thickness 0.15)
				)
				(justify left bottom)
				(hide yes)
			)
		)
		(property "License" "Apache-2.0"
			(at 163.83 36.83 0)
			(effects
				(font
					(size 1.27 1.27)
					(thickness 0.15)
				)
				(justify left bottom)
				(hide yes)
			)
		)
		(property "Author" "Antmicro"
			(at 166.37 36.83 0)
			(effects
				(font
					(size 1.27 1.27)
					(thickness 0.15)
				)
				(justify left bottom)
				(hide yes)
			)
		)
		(property "Val" "4u7"
			(at 143.51 55.8735 90)
			(effects
				(font
					(size 1.27 1.27)
					(thickness 0.15)
				)
				(justify right)
			)
		)
		(property "Voltage" ""
			(at 168.91 36.83 0)
			(effects
				(font
					(size 1.27 1.27)
				)
				(justify left bottom)
				(hide yes)
			)
		)
		(property "Dielectric" ""
			(at 171.45 36.83 0)
			(effects
				(font
					(size 1.27 1.27)
				)
				(justify left bottom)
				(hide yes)
			)
		)
		(pin "1"
		)
		(pin "2"
		)
		(instances
			(project ""
				(path ""
					(reference "C41")
					(unit 1)
				)
			)
		)
	)
	(symbol
		(lib_id "antmicropower:GND")
		(at 105.41 87.63 0)
		(unit 1)
		(exclude_from_sim no)
		(in_bom yes)
		(on_board yes)
		(dnp no)
		(property "Reference" "#PWR0175"
			(at 105.41 93.98 0)
			(effects
				(font
					(size 1.27 1.27)
				)
				(hide yes)
			)
		)
		(property "Value" "GND"
			(at 105.41 91.44 0)
			(effects
				(font
					(size 1.27 1.27)
				)
			)
		)
		(property "Footprint" ""
			(at 105.41 87.63 0)
			(effects
				(font
					(size 1.27 1.27)
				)
				(hide yes)
			)
		)
		(property "Datasheet" ""
			(at 105.41 87.63 0)
			(effects
				(font
					(size 1.27 1.27)
				)
				(hide yes)
			)
		)
		(property "Description" ""
			(at 105.41 87.63 0)
			(effects
				(font
					(size 1.27 1.27)
				)
			)
		)
		(pin "1"
		)
		(instances
			(project ""
				(path ""
					(reference "#PWR0175")
					(unit 1)
				)
			)
		)
	)
	(symbol
		(lib_id "antmicropower:GND")
		(at 132.08 57.15 0)
		(unit 1)
		(exclude_from_sim no)
		(in_bom yes)
		(on_board yes)
		(dnp no)
		(property "Reference" "#PWR0172"
			(at 132.08 63.5 0)
			(effects
				(font
					(size 1.27 1.27)
				)
				(hide yes)
			)
		)
		(property "Value" "GND"
			(at 132.08 60.96 0)
			(effects
				(font
					(size 1.27 1.27)
				)
			)
		)
		(property "Footprint" ""
			(at 132.08 57.15 0)
			(effects
				(font
					(size 1.27 1.27)
				)
				(hide yes)
			)
		)
		(property "Datasheet" ""
			(at 132.08 57.15 0)
			(effects
				(font
					(size 1.27 1.27)
				)
				(hide yes)
			)
		)
		(property "Description" ""
			(at 132.08 57.15 0)
			(effects
				(font
					(size 1.27 1.27)
				)
			)
		)
		(pin "1"
		)
		(instances
			(project ""
				(path ""
					(reference "#PWR0172")
					(unit 1)
				)
			)
		)
	)
	(symbol
		(lib_id "antmicroCapacitors0402:C_4u7_0402")
		(at 105.41 73.66 90)
		(unit 1)
		(exclude_from_sim no)
		(in_bom yes)
		(on_board yes)
		(dnp no)
		(fields_autoplaced yes)
		(property "Reference" "C36"
			(at 107.95 69.8435 90)
			(effects
				(font
					(size 1.27 1.27)
					(thickness 0.15)
				)
				(justify right)
			)
		)
		(property "Value" "C_4u7_0402"
			(at 115.57 53.34 0)
			(effects
				(font
					(size 1.27 1.27)
					(thickness 0.15)
				)
				(justify left bottom)
				(hide yes)
			)
		)
		(property "Footprint" "antmicro-footprints:C_0402_1005Metric"
			(at 118.11 53.34 0)
			(effects
				(font
					(size 1.27 1.27)
					(thickness 0.15)
				)
				(justify left bottom)
				(hide yes)
			)
		)
		(property "Datasheet" "https://www.murata.com/products/productdetail?partno=GRM155R61A475MEAA%23"
			(at 120.65 53.34 0)
			(effects
				(font
					(size 1.27 1.27)
					(thickness 0.15)
				)
				(justify left bottom)
				(hide yes)
			)
		)
		(property "Description" ""
			(at 105.41 73.66 0)
			(effects
				(font
					(size 1.27 1.27)
				)
			)
		)
		(property "MPN" "GRM155R61A475MEAAD"
			(at 123.19 53.34 0)
			(effects
				(font
					(size 1.27 1.27)
					(thickness 0.15)
				)
				(justify left bottom)
				(hide yes)
			)
		)
		(property "Manufacturer" "Murata"
			(at 125.73 53.34 0)
			(effects
				(font
					(size 1.27 1.27)
					(thickness 0.15)
				)
				(justify left bottom)
				(hide yes)
			)
		)
		(property "License" "Apache-2.0"
			(at 128.27 53.34 0)
			(effects
				(font
					(size 1.27 1.27)
					(thickness 0.15)
				)
				(justify left bottom)
				(hide yes)
			)
		)
		(property "Author" "Antmicro"
			(at 130.81 53.34 0)
			(effects
				(font
					(size 1.27 1.27)
					(thickness 0.15)
				)
				(justify left bottom)
				(hide yes)
			)
		)
		(property "Val" "4u7"
			(at 107.95 72.3835 90)
			(effects
				(font
					(size 1.27 1.27)
					(thickness 0.15)
				)
				(justify right)
			)
		)
		(property "Voltage" ""
			(at 133.35 53.34 0)
			(effects
				(font
					(size 1.27 1.27)
				)
				(justify left bottom)
				(hide yes)
			)
		)
		(property "Dielectric" ""
			(at 135.89 53.34 0)
			(effects
				(font
					(size 1.27 1.27)
				)
				(justify left bottom)
				(hide yes)
			)
		)
		(pin "1"
		)
		(pin "2"
		)
		(instances
			(project ""
				(path ""
					(reference "C36")
					(unit 1)
				)
			)
		)
	)
	(symbol
		(lib_id "antmicropower:+0V9")
		(at 260.35 66.04 0)
		(unit 1)
		(exclude_from_sim no)
		(in_bom yes)
		(on_board yes)
		(dnp no)
		(property "Reference" "#PWR0147"
			(at 260.35 69.85 0)
			(effects
				(font
					(size 1.27 1.27)
				)
				(hide yes)
			)
		)
		(property "Value" "+0V9"
			(at 260.35 62.23 0)
			(effects
				(font
					(size 1.27 1.27)
				)
			)
		)
		(property "Footprint" ""
			(at 260.35 66.04 0)
			(effects
				(font
					(size 1.27 1.27)
				)
				(hide yes)
			)
		)
		(property "Datasheet" ""
			(at 260.35 66.04 0)
			(effects
				(font
					(size 1.27 1.27)
				)
				(hide yes)
			)
		)
		(property "Description" ""
			(at 260.35 66.04 0)
			(effects
				(font
					(size 1.27 1.27)
				)
			)
		)
		(pin "1"
		)
		(instances
			(project ""
				(path ""
					(reference "#PWR0147")
					(unit 1)
				)
			)
		)
	)
	(symbol
		(lib_id "antmicropower:+1V05")
		(at 287.02 33.02 0)
		(unit 1)
		(exclude_from_sim no)
		(in_bom yes)
		(on_board yes)
		(dnp no)
		(property "Reference" "#PWR0146"
			(at 287.02 36.83 0)
			(effects
				(font
					(size 1.27 1.27)
				)
				(hide yes)
			)
		)
		(property "Value" "+1V05"
			(at 287.02 29.21 0)
			(effects
				(font
					(size 1.27 1.27)
				)
			)
		)
		(property "Footprint" ""
			(at 287.02 33.02 0)
			(effects
				(font
					(size 1.27 1.27)
				)
				(hide yes)
			)
		)
		(property "Datasheet" ""
			(at 287.02 33.02 0)
			(effects
				(font
					(size 1.27 1.27)
				)
				(hide yes)
			)
		)
		(property "Description" ""
			(at 287.02 33.02 0)
			(effects
				(font
					(size 1.27 1.27)
				)
			)
		)
		(pin "1"
		)
		(instances
			(project ""
				(path ""
					(reference "#PWR0146")
					(unit 1)
				)
			)
		)
	)
	(symbol
		(lib_id "antmicropower:GND")
		(at 140.97 87.63 0)
		(unit 1)
		(exclude_from_sim no)
		(in_bom yes)
		(on_board yes)
		(dnp no)
		(property "Reference" "#PWR0169"
			(at 140.97 93.98 0)
			(effects
				(font
					(size 1.27 1.27)
				)
				(hide yes)
			)
		)
		(property "Value" "GND"
			(at 140.97 91.44 0)
			(effects
				(font
					(size 1.27 1.27)
				)
			)
		)
		(property "Footprint" ""
			(at 140.97 87.63 0)
			(effects
				(font
					(size 1.27 1.27)
				)
				(hide yes)
			)
		)
		(property "Datasheet" ""
			(at 140.97 87.63 0)
			(effects
				(font
					(size 1.27 1.27)
				)
				(hide yes)
			)
		)
		(property "Description" ""
			(at 140.97 87.63 0)
			(effects
				(font
					(size 1.27 1.27)
				)
			)
		)
		(pin "1"
		)
		(instances
			(project ""
				(path ""
					(reference "#PWR0169")
					(unit 1)
				)
			)
		)
	)
	(symbol
		(lib_id "antmicropower:GND")
		(at 229.87 54.61 0)
		(mirror y)
		(unit 1)
		(exclude_from_sim no)
		(in_bom yes)
		(on_board yes)
		(dnp no)
		(property "Reference" "#PWR0181"
			(at 229.87 60.96 0)
			(effects
				(font
					(size 1.27 1.27)
				)
				(hide yes)
			)
		)
		(property "Value" "GND"
			(at 229.87 58.42 0)
			(effects
				(font
					(size 1.27 1.27)
				)
			)
		)
		(property "Footprint" ""
			(at 229.87 54.61 0)
			(effects
				(font
					(size 1.27 1.27)
				)
				(hide yes)
			)
		)
		(property "Datasheet" ""
			(at 229.87 54.61 0)
			(effects
				(font
					(size 1.27 1.27)
				)
				(hide yes)
			)
		)
		(property "Description" ""
			(at 229.87 54.61 0)
			(effects
				(font
					(size 1.27 1.27)
				)
			)
		)
		(pin "1"
		)
		(instances
			(project ""
				(path ""
					(reference "#PWR0181")
					(unit 1)
				)
			)
		)
	)
	(symbol
		(lib_id "antmicropower:GND")
		(at 149.86 57.15 0)
		(unit 1)
		(exclude_from_sim no)
		(in_bom yes)
		(on_board yes)
		(dnp no)
		(property "Reference" "#PWR0183"
			(at 149.86 63.5 0)
			(effects
				(font
					(size 1.27 1.27)
				)
				(hide yes)
			)
		)
		(property "Value" "GND"
			(at 149.86 60.96 0)
			(effects
				(font
					(size 1.27 1.27)
				)
			)
		)
		(property "Footprint" ""
			(at 149.86 57.15 0)
			(effects
				(font
					(size 1.27 1.27)
				)
				(hide yes)
			)
		)
		(property "Datasheet" ""
			(at 149.86 57.15 0)
			(effects
				(font
					(size 1.27 1.27)
				)
				(hide yes)
			)
		)
		(property "Description" ""
			(at 149.86 57.15 0)
			(effects
				(font
					(size 1.27 1.27)
				)
			)
		)
		(pin "1"
		)
		(instances
			(project ""
				(path ""
					(reference "#PWR0183")
					(unit 1)
				)
			)
		)
	)
	(symbol
		(lib_id "antmicropower:GND")
		(at 229.87 87.63 0)
		(unit 1)
		(exclude_from_sim no)
		(in_bom yes)
		(on_board yes)
		(dnp no)
		(property "Reference" "#PWR0194"
			(at 229.87 93.98 0)
			(effects
				(font
					(size 1.27 1.27)
				)
				(hide yes)
			)
		)
		(property "Value" "GND"
			(at 229.87 91.44 0)
			(effects
				(font
					(size 1.27 1.27)
				)
			)
		)
		(property "Footprint" ""
			(at 229.87 87.63 0)
			(effects
				(font
					(size 1.27 1.27)
				)
				(hide yes)
			)
		)
		(property "Datasheet" ""
			(at 229.87 87.63 0)
			(effects
				(font
					(size 1.27 1.27)
				)
				(hide yes)
			)
		)
		(property "Description" ""
			(at 229.87 87.63 0)
			(effects
				(font
					(size 1.27 1.27)
				)
			)
		)
		(pin "1"
		)
		(instances
			(project ""
				(path ""
					(reference "#PWR0194")
					(unit 1)
				)
			)
		)
	)
	(symbol
		(lib_id "antmicroMemory:MT62F1G32D4DR-031")
		(at 236.22 142.24 0)
		(unit 3)
		(exclude_from_sim no)
		(in_bom yes)
		(on_board yes)
		(dnp no)
		(fields_autoplaced yes)
		(property "Reference" "U1"
			(at 253.365 133.985 0)
			(effects
				(font
					(size 1.27 1.27)
				)
			)
		)
		(property "Value" "MT62F1G32D4DR-031"
			(at 280.67 147.32 0)
			(effects
				(font
					(size 1.27 1.27)
				)
				(justify left bottom)
				(hide yes)
			)
		)
		(property "Footprint" "antmicro-footprints:BGA-315_12.4x15mm_Layout15x21_P0.8x0.7mm"
			(at 280.67 154.94 0)
			(effects
				(font
					(size 1.27 1.27)
				)
				(justify left bottom)
				(hide yes)
			)
		)
		(property "Datasheet" "https://www.micron.com/search-results?searchRequest=%7B%22term%22%3A%22MT62F1G32D4DR-031%22%7D"
			(at 280.67 152.4 0)
			(effects
				(font
					(size 1.27 1.27)
				)
				(justify left bottom)
				(hide yes)
			)
		)
		(property "Description" ""
			(at 236.22 142.24 0)
			(effects
				(font
					(size 1.27 1.27)
				)
			)
		)
		(property "Manufacturer" "Micron Technology"
			(at 280.67 149.86 0)
			(effects
				(font
					(size 1.27 1.27)
				)
				(justify left bottom)
				(hide yes)
			)
		)
		(property "MPN" "MT62F1G32D4DR-031 WT:B"
			(at 253.365 136.525 0)
			(effects
				(font
					(size 1.27 1.27)
				)
			)
		)
		(property "Author" "Antmicro"
			(at 280.67 157.48 0)
			(effects
				(font
					(size 1.27 1.27)
				)
				(justify left bottom)
				(hide yes)
			)
		)
		(property "License" "Apache-2.0"
			(at 280.67 160.02 0)
			(effects
				(font
					(size 1.27 1.27)
				)
				(justify left bottom)
				(hide yes)
			)
		)
		(pin "A1"
		)
		(pin "A10"
		)
		(pin "A11"
		)
		(pin "A13"
		)
		(pin "A14"
		)
		(pin "A15"
		)
		(pin "A2"
		)
		(pin "A3"
		)
		(pin "A5"
		)
		(pin "A6"
		)
		(pin "A7"
		)
		(pin "A8"
		)
		(pin "A9"
		)
		(pin "AA1"
		)
		(pin "AA10"
		)
		(pin "AA11"
		)
		(pin "AA13"
		)
		(pin "AA14"
		)
		(pin "AA15"
		)
		(pin "AA2"
		)
		(pin "AA3"
		)
		(pin "AA5"
		)
		(pin "AA6"
		)
		(pin "AA7"
		)
		(pin "AA8"
		)
		(pin "AA9"
		)
		(pin "B1"
		)
		(pin "B10"
		)
		(pin "B12"
		)
		(pin "B14"
		)
		(pin "B15"
		)
		(pin "B2"
		)
		(pin "B4"
		)
		(pin "B6"
		)
		(pin "B7"
		)
		(pin "B8"
		)
		(pin "B9"
		)
		(pin "C1"
		)
		(pin "C11"
		)
		(pin "C13"
		)
		(pin "C15"
		)
		(pin "C3"
		)
		(pin "C5"
		)
		(pin "C7"
		)
		(pin "C8"
		)
		(pin "C9"
		)
		(pin "D10"
		)
		(pin "D12"
		)
		(pin "D14"
		)
		(pin "D2"
		)
		(pin "D4"
		)
		(pin "D6"
		)
		(pin "D7"
		)
		(pin "D8"
		)
		(pin "D9"
		)
		(pin "E1"
		)
		(pin "E11"
		)
		(pin "E13"
		)
		(pin "E15"
		)
		(pin "E3"
		)
		(pin "E5"
		)
		(pin "E7"
		)
		(pin "E8"
		)
		(pin "E9"
		)
		(pin "F1"
		)
		(pin "F10"
		)
		(pin "F12"
		)
		(pin "F13"
		)
		(pin "F14"
		)
		(pin "F15"
		)
		(pin "F2"
		)
		(pin "F3"
		)
		(pin "F4"
		)
		(pin "F6"
		)
		(pin "F7"
		)
		(pin "F8"
		)
		(pin "F9"
		)
		(pin "G1"
		)
		(pin "G11"
		)
		(pin "G13"
		)
		(pin "G14"
		)
		(pin "G15"
		)
		(pin "G2"
		)
		(pin "G3"
		)
		(pin "G5"
		)
		(pin "G7"
		)
		(pin "G9"
		)
		(pin "H1"
		)
		(pin "H10"
		)
		(pin "H12"
		)
		(pin "H14"
		)
		(pin "H15"
		)
		(pin "H2"
		)
		(pin "H3"
		)
		(pin "H4"
		)
		(pin "H6"
		)
		(pin "H8"
		)
		(pin "J1"
		)
		(pin "J10"
		)
		(pin "J11"
		)
		(pin "J12"
		)
		(pin "J13"
		)
		(pin "J14"
		)
		(pin "J15"
		)
		(pin "J2"
		)
		(pin "J3"
		)
		(pin "J4"
		)
		(pin "J5"
		)
		(pin "J6"
		)
		(pin "J7"
		)
		(pin "J8"
		)
		(pin "K1"
		)
		(pin "K10"
		)
		(pin "K11"
		)
		(pin "K12"
		)
		(pin "K13"
		)
		(pin "K14"
		)
		(pin "K15"
		)
		(pin "K2"
		)
		(pin "K3"
		)
		(pin "K4"
		)
		(pin "K5"
		)
		(pin "K6"
		)
		(pin "K7"
		)
		(pin "K8"
		)
		(pin "K9"
		)
		(pin "L1"
		)
		(pin "L10"
		)
		(pin "L11"
		)
		(pin "L12"
		)
		(pin "L13"
		)
		(pin "L14"
		)
		(pin "L15"
		)
		(pin "L2"
		)
		(pin "L3"
		)
		(pin "L4"
		)
		(pin "L5"
		)
		(pin "L6"
		)
		(pin "L7"
		)
		(pin "L8"
		)
		(pin "L9"
		)
		(pin "M1"
		)
		(pin "M10"
		)
		(pin "M11"
		)
		(pin "M12"
		)
		(pin "M13"
		)
		(pin "M14"
		)
		(pin "M15"
		)
		(pin "M2"
		)
		(pin "M3"
		)
		(pin "M4"
		)
		(pin "M5"
		)
		(pin "M6"
		)
		(pin "M7"
		)
		(pin "M8"
		)
		(pin "M9"
		)
		(pin "N1"
		)
		(pin "N10"
		)
		(pin "N11"
		)
		(pin "N12"
		)
		(pin "N13"
		)
		(pin "N14"
		)
		(pin "N15"
		)
		(pin "N2"
		)
		(pin "N3"
		)
		(pin "N4"
		)
		(pin "N5"
		)
		(pin "N6"
		)
		(pin "N8"
		)
		(pin "N9"
		)
		(pin "P1"
		)
		(pin "P10"
		)
		(pin "P12"
		)
		(pin "P13"
		)
		(pin "P14"
		)
		(pin "P15"
		)
		(pin "P2"
		)
		(pin "P4"
		)
		(pin "P6"
		)
		(pin "P8"
		)
		(pin "R1"
		)
		(pin "R11"
		)
		(pin "R13"
		)
		(pin "R14"
		)
		(pin "R15"
		)
		(pin "R2"
		)
		(pin "R3"
		)
		(pin "R5"
		)
		(pin "R7"
		)
		(pin "R9"
		)
		(pin "T1"
		)
		(pin "T10"
		)
		(pin "T12"
		)
		(pin "T13"
		)
		(pin "T14"
		)
		(pin "T15"
		)
		(pin "T2"
		)
		(pin "T3"
		)
		(pin "T4"
		)
		(pin "T6"
		)
		(pin "T7"
		)
		(pin "T8"
		)
		(pin "T9"
		)
		(pin "U1"
		)
		(pin "U11"
		)
		(pin "U13"
		)
		(pin "U15"
		)
		(pin "U3"
		)
		(pin "U5"
		)
		(pin "U7"
		)
		(pin "U8"
		)
		(pin "U9"
		)
		(pin "V10"
		)
		(pin "V12"
		)
		(pin "V14"
		)
		(pin "V2"
		)
		(pin "V4"
		)
		(pin "V6"
		)
		(pin "V7"
		)
		(pin "V8"
		)
		(pin "V9"
		)
		(pin "W1"
		)
		(pin "W11"
		)
		(pin "W13"
		)
		(pin "W15"
		)
		(pin "W3"
		)
		(pin "W5"
		)
		(pin "W7"
		)
		(pin "W8"
		)
		(pin "W9"
		)
		(pin "Y1"
		)
		(pin "Y10"
		)
		(pin "Y12"
		)
		(pin "Y14"
		)
		(pin "Y15"
		)
		(pin "Y2"
		)
		(pin "Y4"
		)
		(pin "Y6"
		)
		(pin "Y7"
		)
		(pin "Y8"
		)
		(pin "Y9"
		)
		(pin "A12"
		)
		(pin "A4"
		)
		(pin "B11"
		)
		(pin "B13"
		)
		(pin "B3"
		)
		(pin "B5"
		)
		(pin "C10"
		)
		(pin "C12"
		)
		(pin "C14"
		)
		(pin "C2"
		)
		(pin "C4"
		)
		(pin "C6"
		)
		(pin "D1"
		)
		(pin "D11"
		)
		(pin "D13"
		)
		(pin "D15"
		)
		(pin "D3"
		)
		(pin "D5"
		)
		(pin "E10"
		)
		(pin "E12"
		)
		(pin "E14"
		)
		(pin "E2"
		)
		(pin "E4"
		)
		(pin "E6"
		)
		(pin "F11"
		)
		(pin "F5"
		)
		(pin "G10"
		)
		(pin "G12"
		)
		(pin "G4"
		)
		(pin "G6"
		)
		(pin "G8"
		)
		(pin "H11"
		)
		(pin "H13"
		)
		(pin "H5"
		)
		(pin "H7"
		)
		(pin "H9"
		)
		(pin "J9"
		)
		(pin "AA12"
		)
		(pin "AA4"
		)
		(pin "N7"
		)
		(pin "P11"
		)
		(pin "P3"
		)
		(pin "P5"
		)
		(pin "P7"
		)
		(pin "P9"
		)
		(pin "R10"
		)
		(pin "R12"
		)
		(pin "R4"
		)
		(pin "R6"
		)
		(pin "R8"
		)
		(pin "T11"
		)
		(pin "T5"
		)
		(pin "U10"
		)
		(pin "U12"
		)
		(pin "U14"
		)
		(pin "U2"
		)
		(pin "U4"
		)
		(pin "U6"
		)
		(pin "V1"
		)
		(pin "V11"
		)
		(pin "V13"
		)
		(pin "V15"
		)
		(pin "V3"
		)
		(pin "V5"
		)
		(pin "W10"
		)
		(pin "W12"
		)
		(pin "W14"
		)
		(pin "W2"
		)
		(pin "W4"
		)
		(pin "W6"
		)
		(pin "Y11"
		)
		(pin "Y13"
		)
		(pin "Y3"
		)
		(pin "Y5"
		)
		(instances
			(project ""
				(path ""
					(reference "U1")
					(unit 3)
				)
			)
		)
	)
	(symbol
		(lib_id "antmicroCapacitors0402:C_4u7_0402")
		(at 229.87 40.64 270)
		(mirror x)
		(unit 1)
		(exclude_from_sim no)
		(in_bom yes)
		(on_board yes)
		(dnp no)
		(fields_autoplaced yes)
		(property "Reference" "C53"
			(at 227.33 36.8235 90)
			(effects
				(font
					(size 1.27 1.27)
					(thickness 0.15)
				)
				(justify right)
			)
		)
		(property "Value" "C_4u7_0402"
			(at 219.71 20.32 0)
			(effects
				(font
					(size 1.27 1.27)
					(thickness 0.15)
				)
				(justify left bottom)
				(hide yes)
			)
		)
		(property "Footprint" "antmicro-footprints:C_0402_1005Metric"
			(at 217.17 20.32 0)
			(effects
				(font
					(size 1.27 1.27)
					(thickness 0.15)
				)
				(justify left bottom)
				(hide yes)
			)
		)
		(property "Datasheet" "https://www.murata.com/products/productdetail?partno=GRM155R61A475MEAA%23"
			(at 214.63 20.32 0)
			(effects
				(font
					(size 1.27 1.27)
					(thickness 0.15)
				)
				(justify left bottom)
				(hide yes)
			)
		)
		(property "Description" ""
			(at 229.87 40.64 0)
			(effects
				(font
					(size 1.27 1.27)
				)
			)
		)
		(property "MPN" "GRM155R61A475MEAAD"
			(at 212.09 20.32 0)
			(effects
				(font
					(size 1.27 1.27)
					(thickness 0.15)
				)
				(justify left bottom)
				(hide yes)
			)
		)
		(property "Manufacturer" "Murata"
			(at 209.55 20.32 0)
			(effects
				(font
					(size 1.27 1.27)
					(thickness 0.15)
				)
				(justify left bottom)
				(hide yes)
			)
		)
		(property "License" "Apache-2.0"
			(at 207.01 20.32 0)
			(effects
				(font
					(size 1.27 1.27)
					(thickness 0.15)
				)
				(justify left bottom)
				(hide yes)
			)
		)
		(property "Author" "Antmicro"
			(at 204.47 20.32 0)
			(effects
				(font
					(size 1.27 1.27)
					(thickness 0.15)
				)
				(justify left bottom)
				(hide yes)
			)
		)
		(property "Val" "4u7"
			(at 227.33 39.3635 90)
			(effects
				(font
					(size 1.27 1.27)
					(thickness 0.15)
				)
				(justify right)
			)
		)
		(property "Voltage" ""
			(at 201.93 20.32 0)
			(effects
				(font
					(size 1.27 1.27)
				)
				(justify left bottom)
				(hide yes)
			)
		)
		(property "Dielectric" ""
			(at 199.39 20.32 0)
			(effects
				(font
					(size 1.27 1.27)
				)
				(justify left bottom)
				(hide yes)
			)
		)
		(pin "1"
		)
		(pin "2"
		)
		(instances
			(project ""
				(path ""
					(reference "C53")
					(unit 1)
				)
			)
		)
	)
	(symbol
		(lib_id "antmicroCapacitors0402:C_4u7_0402")
		(at 149.86 73.66 90)
		(unit 1)
		(exclude_from_sim no)
		(in_bom yes)
		(on_board yes)
		(dnp no)
		(fields_autoplaced yes)
		(property "Reference" "C49"
			(at 152.4 69.8435 90)
			(effects
				(font
					(size 1.27 1.27)
					(thickness 0.15)
				)
				(justify right)
			)
		)
		(property "Value" "C_4u7_0402"
			(at 160.02 53.34 0)
			(effects
				(font
					(size 1.27 1.27)
					(thickness 0.15)
				)
				(justify left bottom)
				(hide yes)
			)
		)
		(property "Footprint" "antmicro-footprints:C_0402_1005Metric"
			(at 162.56 53.34 0)
			(effects
				(font
					(size 1.27 1.27)
					(thickness 0.15)
				)
				(justify left bottom)
				(hide yes)
			)
		)
		(property "Datasheet" "https://www.murata.com/products/productdetail?partno=GRM155R61A475MEAA%23"
			(at 165.1 53.34 0)
			(effects
				(font
					(size 1.27 1.27)
					(thickness 0.15)
				)
				(justify left bottom)
				(hide yes)
			)
		)
		(property "Description" ""
			(at 149.86 73.66 0)
			(effects
				(font
					(size 1.27 1.27)
				)
			)
		)
		(property "MPN" "GRM155R61A475MEAAD"
			(at 167.64 53.34 0)
			(effects
				(font
					(size 1.27 1.27)
					(thickness 0.15)
				)
				(justify left bottom)
				(hide yes)
			)
		)
		(property "Manufacturer" "Murata"
			(at 170.18 53.34 0)
			(effects
				(font
					(size 1.27 1.27)
					(thickness 0.15)
				)
				(justify left bottom)
				(hide yes)
			)
		)
		(property "License" "Apache-2.0"
			(at 172.72 53.34 0)
			(effects
				(font
					(size 1.27 1.27)
					(thickness 0.15)
				)
				(justify left bottom)
				(hide yes)
			)
		)
		(property "Author" "Antmicro"
			(at 175.26 53.34 0)
			(effects
				(font
					(size 1.27 1.27)
					(thickness 0.15)
				)
				(justify left bottom)
				(hide yes)
			)
		)
		(property "Val" "4u7"
			(at 152.4 72.3835 90)
			(effects
				(font
					(size 1.27 1.27)
					(thickness 0.15)
				)
				(justify right)
			)
		)
		(property "Voltage" ""
			(at 177.8 53.34 0)
			(effects
				(font
					(size 1.27 1.27)
				)
				(justify left bottom)
				(hide yes)
			)
		)
		(property "Dielectric" ""
			(at 180.34 53.34 0)
			(effects
				(font
					(size 1.27 1.27)
				)
				(justify left bottom)
				(hide yes)
			)
		)
		(pin "1"
		)
		(pin "2"
		)
		(instances
			(project ""
				(path ""
					(reference "C49")
					(unit 1)
				)
			)
		)
	)
	(symbol
		(lib_id "antmicropower:GND")
		(at 274.32 40.64 0)
		(mirror y)
		(unit 1)
		(exclude_from_sim no)
		(in_bom yes)
		(on_board yes)
		(dnp no)
		(property "Reference" "#PWR0196"
			(at 274.32 46.99 0)
			(effects
				(font
					(size 1.27 1.27)
				)
				(hide yes)
			)
		)
		(property "Value" "GND"
			(at 274.32 44.45 0)
			(effects
				(font
					(size 1.27 1.27)
				)
			)
		)
		(property "Footprint" ""
			(at 274.32 40.64 0)
			(effects
				(font
					(size 1.27 1.27)
				)
				(hide yes)
			)
		)
		(property "Datasheet" ""
			(at 274.32 40.64 0)
			(effects
				(font
					(size 1.27 1.27)
				)
				(hide yes)
			)
		)
		(property "Description" ""
			(at 274.32 40.64 0)
			(effects
				(font
					(size 1.27 1.27)
				)
			)
		)
		(pin "1"
		)
		(instances
			(project ""
				(path ""
					(reference "#PWR0196")
					(unit 1)
				)
			)
		)
	)
	(symbol
		(lib_id "antmicropower:GND")
		(at 132.08 73.66 0)
		(unit 1)
		(exclude_from_sim no)
		(in_bom yes)
		(on_board yes)
		(dnp no)
		(property "Reference" "#PWR0184"
			(at 132.08 80.01 0)
			(effects
				(font
					(size 1.27 1.27)
				)
				(hide yes)
			)
		)
		(property "Value" "GND"
			(at 132.08 77.47 0)
			(effects
				(font
					(size 1.27 1.27)
				)
			)
		)
		(property "Footprint" ""
			(at 132.08 73.66 0)
			(effects
				(font
					(size 1.27 1.27)
				)
				(hide yes)
			)
		)
		(property "Datasheet" ""
			(at 132.08 73.66 0)
			(effects
				(font
					(size 1.27 1.27)
				)
				(hide yes)
			)
		)
		(property "Description" ""
			(at 132.08 73.66 0)
			(effects
				(font
					(size 1.27 1.27)
				)
			)
		)
		(pin "1"
		)
		(instances
			(project ""
				(path ""
					(reference "#PWR0184")
					(unit 1)
				)
			)
		)
	)
	(symbol
		(lib_id "antmicroCapacitors0402:C_4u7_0402")
		(at 283.21 54.61 270)
		(mirror x)
		(unit 1)
		(exclude_from_sim no)
		(in_bom yes)
		(on_board yes)
		(dnp no)
		(fields_autoplaced yes)
		(property "Reference" "C77"
			(at 280.67 50.7935 90)
			(effects
				(font
					(size 1.27 1.27)
					(thickness 0.15)
				)
				(justify right)
			)
		)
		(property "Value" "C_4u7_0402"
			(at 273.05 34.29 0)
			(effects
				(font
					(size 1.27 1.27)
					(thickness 0.15)
				)
				(justify left bottom)
				(hide yes)
			)
		)
		(property "Footprint" "antmicro-footprints:C_0402_1005Metric"
			(at 270.51 34.29 0)
			(effects
				(font
					(size 1.27 1.27)
					(thickness 0.15)
				)
				(justify left bottom)
				(hide yes)
			)
		)
		(property "Datasheet" "https://www.murata.com/products/productdetail?partno=GRM155R61A475MEAA%23"
			(at 267.97 34.29 0)
			(effects
				(font
					(size 1.27 1.27)
					(thickness 0.15)
				)
				(justify left bottom)
				(hide yes)
			)
		)
		(property "Description" ""
			(at 283.21 54.61 0)
			(effects
				(font
					(size 1.27 1.27)
				)
			)
		)
		(property "MPN" "GRM155R61A475MEAAD"
			(at 265.43 34.29 0)
			(effects
				(font
					(size 1.27 1.27)
					(thickness 0.15)
				)
				(justify left bottom)
				(hide yes)
			)
		)
		(property "Manufacturer" "Murata"
			(at 262.89 34.29 0)
			(effects
				(font
					(size 1.27 1.27)
					(thickness 0.15)
				)
				(justify left bottom)
				(hide yes)
			)
		)
		(property "License" "Apache-2.0"
			(at 260.35 34.29 0)
			(effects
				(font
					(size 1.27 1.27)
					(thickness 0.15)
				)
				(justify left bottom)
				(hide yes)
			)
		)
		(property "Author" "Antmicro"
			(at 257.81 34.29 0)
			(effects
				(font
					(size 1.27 1.27)
					(thickness 0.15)
				)
				(justify left bottom)
				(hide yes)
			)
		)
		(property "Val" "4u7"
			(at 280.67 53.3335 90)
			(effects
				(font
					(size 1.27 1.27)
					(thickness 0.15)
				)
				(justify right)
			)
		)
		(property "Voltage" ""
			(at 255.27 34.29 0)
			(effects
				(font
					(size 1.27 1.27)
				)
				(justify left bottom)
				(hide yes)
			)
		)
		(property "Dielectric" ""
			(at 252.73 34.29 0)
			(effects
				(font
					(size 1.27 1.27)
				)
				(justify left bottom)
				(hide yes)
			)
		)
		(pin "1"
		)
		(pin "2"
		)
		(instances
			(project ""
				(path ""
					(reference "C77")
					(unit 1)
				)
			)
		)
	)
	(symbol
		(lib_id "antmicropower:GND")
		(at 140.97 73.66 0)
		(unit 1)
		(exclude_from_sim no)
		(in_bom yes)
		(on_board yes)
		(dnp no)
		(property "Reference" "#PWR0185"
			(at 140.97 80.01 0)
			(effects
				(font
					(size 1.27 1.27)
				)
				(hide yes)
			)
		)
		(property "Value" "GND"
			(at 140.97 77.47 0)
			(effects
				(font
					(size 1.27 1.27)
				)
			)
		)
		(property "Footprint" ""
			(at 140.97 73.66 0)
			(effects
				(font
					(size 1.27 1.27)
				)
				(hide yes)
			)
		)
		(property "Datasheet" ""
			(at 140.97 73.66 0)
			(effects
				(font
					(size 1.27 1.27)
				)
				(hide yes)
			)
		)
		(property "Description" ""
			(at 140.97 73.66 0)
			(effects
				(font
					(size 1.27 1.27)
				)
			)
		)
		(pin "1"
		)
		(instances
			(project ""
				(path ""
					(reference "#PWR0185")
					(unit 1)
				)
			)
		)
	)
	(symbol
		(lib_id "antmicropower:GND")
		(at 247.65 40.64 0)
		(mirror y)
		(unit 1)
		(exclude_from_sim no)
		(in_bom yes)
		(on_board yes)
		(dnp no)
		(property "Reference" "#PWR0197"
			(at 247.65 46.99 0)
			(effects
				(font
					(size 1.27 1.27)
				)
				(hide yes)
			)
		)
		(property "Value" "GND"
			(at 247.65 44.45 0)
			(effects
				(font
					(size 1.27 1.27)
				)
			)
		)
		(property "Footprint" ""
			(at 247.65 40.64 0)
			(effects
				(font
					(size 1.27 1.27)
				)
				(hide yes)
			)
		)
		(property "Datasheet" ""
			(at 247.65 40.64 0)
			(effects
				(font
					(size 1.27 1.27)
				)
				(hide yes)
			)
		)
		(property "Description" ""
			(at 247.65 40.64 0)
			(effects
				(font
					(size 1.27 1.27)
				)
			)
		)
		(pin "1"
		)
		(instances
			(project ""
				(path ""
					(reference "#PWR0197")
					(unit 1)
				)
			)
		)
	)
	(symbol
		(lib_id "antmicroCapacitors0402:C_4u7_0402")
		(at 123.19 57.15 90)
		(unit 1)
		(exclude_from_sim no)
		(in_bom yes)
		(on_board yes)
		(dnp no)
		(fields_autoplaced yes)
		(property "Reference" "C35"
			(at 125.73 53.3335 90)
			(effects
				(font
					(size 1.27 1.27)
					(thickness 0.15)
				)
				(justify right)
			)
		)
		(property "Value" "C_4u7_0402"
			(at 133.35 36.83 0)
			(effects
				(font
					(size 1.27 1.27)
					(thickness 0.15)
				)
				(justify left bottom)
				(hide yes)
			)
		)
		(property "Footprint" "antmicro-footprints:C_0402_1005Metric"
			(at 135.89 36.83 0)
			(effects
				(font
					(size 1.27 1.27)
					(thickness 0.15)
				)
				(justify left bottom)
				(hide yes)
			)
		)
		(property "Datasheet" "https://www.murata.com/products/productdetail?partno=GRM155R61A475MEAA%23"
			(at 138.43 36.83 0)
			(effects
				(font
					(size 1.27 1.27)
					(thickness 0.15)
				)
				(justify left bottom)
				(hide yes)
			)
		)
		(property "Description" ""
			(at 123.19 57.15 0)
			(effects
				(font
					(size 1.27 1.27)
				)
			)
		)
		(property "MPN" "GRM155R61A475MEAAD"
			(at 140.97 36.83 0)
			(effects
				(font
					(size 1.27 1.27)
					(thickness 0.15)
				)
				(justify left bottom)
				(hide yes)
			)
		)
		(property "Manufacturer" "Murata"
			(at 143.51 36.83 0)
			(effects
				(font
					(size 1.27 1.27)
					(thickness 0.15)
				)
				(justify left bottom)
				(hide yes)
			)
		)
		(property "License" "Apache-2.0"
			(at 146.05 36.83 0)
			(effects
				(font
					(size 1.27 1.27)
					(thickness 0.15)
				)
				(justify left bottom)
				(hide yes)
			)
		)
		(property "Author" "Antmicro"
			(at 148.59 36.83 0)
			(effects
				(font
					(size 1.27 1.27)
					(thickness 0.15)
				)
				(justify left bottom)
				(hide yes)
			)
		)
		(property "Val" "4u7"
			(at 125.73 55.8735 90)
			(effects
				(font
					(size 1.27 1.27)
					(thickness 0.15)
				)
				(justify right)
			)
		)
		(property "Voltage" ""
			(at 151.13 36.83 0)
			(effects
				(font
					(size 1.27 1.27)
				)
				(justify left bottom)
				(hide yes)
			)
		)
		(property "Dielectric" ""
			(at 153.67 36.83 0)
			(effects
				(font
					(size 1.27 1.27)
				)
				(justify left bottom)
				(hide yes)
			)
		)
		(pin "1"
		)
		(pin "2"
		)
		(instances
			(project ""
				(path ""
					(reference "C35")
					(unit 1)
				)
			)
		)
	)
	(symbol
		(lib_id "antmicroCapacitors0402:C_4u7_0402")
		(at 238.76 87.63 90)
		(unit 1)
		(exclude_from_sim no)
		(in_bom yes)
		(on_board yes)
		(dnp no)
		(fields_autoplaced yes)
		(property "Reference" "C56"
			(at 241.3 83.8135 90)
			(effects
				(font
					(size 1.27 1.27)
					(thickness 0.15)
				)
				(justify right)
			)
		)
		(property "Value" "C_4u7_0402"
			(at 248.92 67.31 0)
			(effects
				(font
					(size 1.27 1.27)
					(thickness 0.15)
				)
				(justify left bottom)
				(hide yes)
			)
		)
		(property "Footprint" "antmicro-footprints:C_0402_1005Metric"
			(at 251.46 67.31 0)
			(effects
				(font
					(size 1.27 1.27)
					(thickness 0.15)
				)
				(justify left bottom)
				(hide yes)
			)
		)
		(property "Datasheet" "https://www.murata.com/products/productdetail?partno=GRM155R61A475MEAA%23"
			(at 254 67.31 0)
			(effects
				(font
					(size 1.27 1.27)
					(thickness 0.15)
				)
				(justify left bottom)
				(hide yes)
			)
		)
		(property "Description" ""
			(at 238.76 87.63 0)
			(effects
				(font
					(size 1.27 1.27)
				)
			)
		)
		(property "MPN" "GRM155R61A475MEAAD"
			(at 256.54 67.31 0)
			(effects
				(font
					(size 1.27 1.27)
					(thickness 0.15)
				)
				(justify left bottom)
				(hide yes)
			)
		)
		(property "Manufacturer" "Murata"
			(at 259.08 67.31 0)
			(effects
				(font
					(size 1.27 1.27)
					(thickness 0.15)
				)
				(justify left bottom)
				(hide yes)
			)
		)
		(property "License" "Apache-2.0"
			(at 261.62 67.31 0)
			(effects
				(font
					(size 1.27 1.27)
					(thickness 0.15)
				)
				(justify left bottom)
				(hide yes)
			)
		)
		(property "Author" "Antmicro"
			(at 264.16 67.31 0)
			(effects
				(font
					(size 1.27 1.27)
					(thickness 0.15)
				)
				(justify left bottom)
				(hide yes)
			)
		)
		(property "Val" "4u7"
			(at 241.3 86.3535 90)
			(effects
				(font
					(size 1.27 1.27)
					(thickness 0.15)
				)
				(justify right)
			)
		)
		(property "Voltage" ""
			(at 266.7 67.31 0)
			(effects
				(font
					(size 1.27 1.27)
				)
				(justify left bottom)
				(hide yes)
			)
		)
		(property "Dielectric" ""
			(at 269.24 67.31 0)
			(effects
				(font
					(size 1.27 1.27)
				)
				(justify left bottom)
				(hide yes)
			)
		)
		(pin "1"
		)
		(pin "2"
		)
		(instances
			(project ""
				(path ""
					(reference "C56")
					(unit 1)
				)
			)
		)
	)
	(symbol
		(lib_id "antmicroCapacitors0402:C_4u7_0402")
		(at 132.08 87.63 90)
		(unit 1)
		(exclude_from_sim no)
		(in_bom yes)
		(on_board yes)
		(dnp no)
		(fields_autoplaced yes)
		(property "Reference" "C46"
			(at 134.62 83.8135 90)
			(effects
				(font
					(size 1.27 1.27)
					(thickness 0.15)
				)
				(justify right)
			)
		)
		(property "Value" "C_4u7_0402"
			(at 142.24 67.31 0)
			(effects
				(font
					(size 1.27 1.27)
					(thickness 0.15)
				)
				(justify left bottom)
				(hide yes)
			)
		)
		(property "Footprint" "antmicro-footprints:C_0402_1005Metric"
			(at 144.78 67.31 0)
			(effects
				(font
					(size 1.27 1.27)
					(thickness 0.15)
				)
				(justify left bottom)
				(hide yes)
			)
		)
		(property "Datasheet" "https://www.murata.com/products/productdetail?partno=GRM155R61A475MEAA%23"
			(at 147.32 67.31 0)
			(effects
				(font
					(size 1.27 1.27)
					(thickness 0.15)
				)
				(justify left bottom)
				(hide yes)
			)
		)
		(property "Description" ""
			(at 132.08 87.63 0)
			(effects
				(font
					(size 1.27 1.27)
				)
			)
		)
		(property "MPN" "GRM155R61A475MEAAD"
			(at 149.86 67.31 0)
			(effects
				(font
					(size 1.27 1.27)
					(thickness 0.15)
				)
				(justify left bottom)
				(hide yes)
			)
		)
		(property "Manufacturer" "Murata"
			(at 152.4 67.31 0)
			(effects
				(font
					(size 1.27 1.27)
					(thickness 0.15)
				)
				(justify left bottom)
				(hide yes)
			)
		)
		(property "License" "Apache-2.0"
			(at 154.94 67.31 0)
			(effects
				(font
					(size 1.27 1.27)
					(thickness 0.15)
				)
				(justify left bottom)
				(hide yes)
			)
		)
		(property "Author" "Antmicro"
			(at 157.48 67.31 0)
			(effects
				(font
					(size 1.27 1.27)
					(thickness 0.15)
				)
				(justify left bottom)
				(hide yes)
			)
		)
		(property "Val" "4u7"
			(at 134.62 86.3535 90)
			(effects
				(font
					(size 1.27 1.27)
					(thickness 0.15)
				)
				(justify right)
			)
		)
		(property "Voltage" ""
			(at 160.02 67.31 0)
			(effects
				(font
					(size 1.27 1.27)
				)
				(justify left bottom)
				(hide yes)
			)
		)
		(property "Dielectric" ""
			(at 162.56 67.31 0)
			(effects
				(font
					(size 1.27 1.27)
				)
				(justify left bottom)
				(hide yes)
			)
		)
		(pin "1"
		)
		(pin "2"
		)
		(instances
			(project ""
				(path ""
					(reference "C46")
					(unit 1)
				)
			)
		)
	)
	(symbol
		(lib_id "antmicropower:+0V5")
		(at 100.33 66.04 0)
		(unit 1)
		(exclude_from_sim no)
		(in_bom yes)
		(on_board yes)
		(dnp no)
		(property "Reference" "#PWR0148"
			(at 100.33 69.85 0)
			(effects
				(font
					(size 1.27 1.27)
				)
				(hide yes)
			)
		)
		(property "Value" "+0V5"
			(at 99.695 62.23 0)
			(effects
				(font
					(size 1.27 1.27)
				)
			)
		)
		(property "Footprint" ""
			(at 100.33 66.04 0)
			(effects
				(font
					(size 1.27 1.27)
				)
				(hide yes)
			)
		)
		(property "Datasheet" ""
			(at 100.33 66.04 0)
			(effects
				(font
					(size 1.27 1.27)
				)
				(hide yes)
			)
		)
		(property "Description" ""
			(at 100.33 66.04 0)
			(effects
				(font
					(size 1.27 1.27)
				)
			)
		)
		(pin "1"
		)
		(instances
			(project ""
				(path ""
					(reference "#PWR0148")
					(unit 1)
				)
			)
		)
	)
	(symbol
		(lib_id "antmicroCapacitors0402:C_4u7_0402")
		(at 247.65 54.61 270)
		(mirror x)
		(unit 1)
		(exclude_from_sim no)
		(in_bom yes)
		(on_board yes)
		(dnp no)
		(fields_autoplaced yes)
		(property "Reference" "C62"
			(at 245.11 50.7935 90)
			(effects
				(font
					(size 1.27 1.27)
					(thickness 0.15)
				)
				(justify right)
			)
		)
		(property "Value" "C_4u7_0402"
			(at 237.49 34.29 0)
			(effects
				(font
					(size 1.27 1.27)
					(thickness 0.15)
				)
				(justify left bottom)
				(hide yes)
			)
		)
		(property "Footprint" "antmicro-footprints:C_0402_1005Metric"
			(at 234.95 34.29 0)
			(effects
				(font
					(size 1.27 1.27)
					(thickness 0.15)
				)
				(justify left bottom)
				(hide yes)
			)
		)
		(property "Datasheet" "https://www.murata.com/products/productdetail?partno=GRM155R61A475MEAA%23"
			(at 232.41 34.29 0)
			(effects
				(font
					(size 1.27 1.27)
					(thickness 0.15)
				)
				(justify left bottom)
				(hide yes)
			)
		)
		(property "Description" ""
			(at 247.65 54.61 0)
			(effects
				(font
					(size 1.27 1.27)
				)
			)
		)
		(property "MPN" "GRM155R61A475MEAAD"
			(at 229.87 34.29 0)
			(effects
				(font
					(size 1.27 1.27)
					(thickness 0.15)
				)
				(justify left bottom)
				(hide yes)
			)
		)
		(property "Manufacturer" "Murata"
			(at 227.33 34.29 0)
			(effects
				(font
					(size 1.27 1.27)
					(thickness 0.15)
				)
				(justify left bottom)
				(hide yes)
			)
		)
		(property "License" "Apache-2.0"
			(at 224.79 34.29 0)
			(effects
				(font
					(size 1.27 1.27)
					(thickness 0.15)
				)
				(justify left bottom)
				(hide yes)
			)
		)
		(property "Author" "Antmicro"
			(at 222.25 34.29 0)
			(effects
				(font
					(size 1.27 1.27)
					(thickness 0.15)
				)
				(justify left bottom)
				(hide yes)
			)
		)
		(property "Val" "4u7"
			(at 245.11 53.3335 90)
			(effects
				(font
					(size 1.27 1.27)
					(thickness 0.15)
				)
				(justify right)
			)
		)
		(property "Voltage" ""
			(at 219.71 34.29 0)
			(effects
				(font
					(size 1.27 1.27)
				)
				(justify left bottom)
				(hide yes)
			)
		)
		(property "Dielectric" ""
			(at 217.17 34.29 0)
			(effects
				(font
					(size 1.27 1.27)
				)
				(justify left bottom)
				(hide yes)
			)
		)
		(pin "1"
		)
		(pin "2"
		)
		(instances
			(project ""
				(path ""
					(reference "C62")
					(unit 1)
				)
			)
		)
	)
	(symbol
		(lib_id "antmicroCapacitors0402:C_4u7_0402")
		(at 256.54 87.63 90)
		(unit 1)
		(exclude_from_sim no)
		(in_bom yes)
		(on_board yes)
		(dnp no)
		(fields_autoplaced yes)
		(property "Reference" "C64"
			(at 259.08 83.8135 90)
			(effects
				(font
					(size 1.27 1.27)
					(thickness 0.15)
				)
				(justify right)
			)
		)
		(property "Value" "C_4u7_0402"
			(at 266.7 67.31 0)
			(effects
				(font
					(size 1.27 1.27)
					(thickness 0.15)
				)
				(justify left bottom)
				(hide yes)
			)
		)
		(property "Footprint" "antmicro-footprints:C_0402_1005Metric"
			(at 269.24 67.31 0)
			(effects
				(font
					(size 1.27 1.27)
					(thickness 0.15)
				)
				(justify left bottom)
				(hide yes)
			)
		)
		(property "Datasheet" "https://www.murata.com/products/productdetail?partno=GRM155R61A475MEAA%23"
			(at 271.78 67.31 0)
			(effects
				(font
					(size 1.27 1.27)
					(thickness 0.15)
				)
				(justify left bottom)
				(hide yes)
			)
		)
		(property "Description" ""
			(at 256.54 87.63 0)
			(effects
				(font
					(size 1.27 1.27)
				)
			)
		)
		(property "MPN" "GRM155R61A475MEAAD"
			(at 274.32 67.31 0)
			(effects
				(font
					(size 1.27 1.27)
					(thickness 0.15)
				)
				(justify left bottom)
				(hide yes)
			)
		)
		(property "Manufacturer" "Murata"
			(at 276.86 67.31 0)
			(effects
				(font
					(size 1.27 1.27)
					(thickness 0.15)
				)
				(justify left bottom)
				(hide yes)
			)
		)
		(property "License" "Apache-2.0"
			(at 279.4 67.31 0)
			(effects
				(font
					(size 1.27 1.27)
					(thickness 0.15)
				)
				(justify left bottom)
				(hide yes)
			)
		)
		(property "Author" "Antmicro"
			(at 281.94 67.31 0)
			(effects
				(font
					(size 1.27 1.27)
					(thickness 0.15)
				)
				(justify left bottom)
				(hide yes)
			)
		)
		(property "Val" "4u7"
			(at 259.08 86.3535 90)
			(effects
				(font
					(size 1.27 1.27)
					(thickness 0.15)
				)
				(justify right)
			)
		)
		(property "Voltage" ""
			(at 284.48 67.31 0)
			(effects
				(font
					(size 1.27 1.27)
				)
				(justify left bottom)
				(hide yes)
			)
		)
		(property "Dielectric" ""
			(at 287.02 67.31 0)
			(effects
				(font
					(size 1.27 1.27)
				)
				(justify left bottom)
				(hide yes)
			)
		)
		(pin "1"
		)
		(pin "2"
		)
		(instances
			(project ""
				(path ""
					(reference "C64")
					(unit 1)
				)
			)
		)
	)
	(symbol
		(lib_id "antmicropower:GND")
		(at 238.76 40.64 0)
		(mirror y)
		(unit 1)
		(exclude_from_sim no)
		(in_bom yes)
		(on_board yes)
		(dnp no)
		(property "Reference" "#PWR0180"
			(at 238.76 46.99 0)
			(effects
				(font
					(size 1.27 1.27)
				)
				(hide yes)
			)
		)
		(property "Value" "GND"
			(at 238.76 44.45 0)
			(effects
				(font
					(size 1.27 1.27)
				)
			)
		)
		(property "Footprint" ""
			(at 238.76 40.64 0)
			(effects
				(font
					(size 1.27 1.27)
				)
				(hide yes)
			)
		)
		(property "Datasheet" ""
			(at 238.76 40.64 0)
			(effects
				(font
					(size 1.27 1.27)
				)
				(hide yes)
			)
		)
		(property "Description" ""
			(at 238.76 40.64 0)
			(effects
				(font
					(size 1.27 1.27)
				)
			)
		)
		(pin "1"
		)
		(instances
			(project ""
				(path ""
					(reference "#PWR0180")
					(unit 1)
				)
			)
		)
	)
	(symbol
		(lib_id "antmicropower:GND")
		(at 283.21 54.61 0)
		(mirror y)
		(unit 1)
		(exclude_from_sim no)
		(in_bom yes)
		(on_board yes)
		(dnp no)
		(property "Reference" "#PWR0271"
			(at 283.21 60.96 0)
			(effects
				(font
					(size 1.27 1.27)
				)
				(hide yes)
			)
		)
		(property "Value" "GND"
			(at 283.21 58.42 0)
			(effects
				(font
					(size 1.27 1.27)
				)
			)
		)
		(property "Footprint" ""
			(at 283.21 54.61 0)
			(effects
				(font
					(size 1.27 1.27)
				)
				(hide yes)
			)
		)
		(property "Datasheet" ""
			(at 283.21 54.61 0)
			(effects
				(font
					(size 1.27 1.27)
				)
				(hide yes)
			)
		)
		(property "Description" ""
			(at 283.21 54.61 0)
			(effects
				(font
					(size 1.27 1.27)
				)
			)
		)
		(pin "1"
		)
		(instances
			(project ""
				(path ""
					(reference "#PWR0271")
					(unit 1)
				)
			)
		)
	)
	(symbol
		(lib_id "antmicropower:+1V8")
		(at 119.38 49.53 0)
		(unit 1)
		(exclude_from_sim no)
		(in_bom yes)
		(on_board yes)
		(dnp no)
		(property "Reference" "#PWR0165"
			(at 134.62 52.07 0)
			(effects
				(font
					(size 1.27 1.27)
					(thickness 0.15)
				)
				(justify left bottom)
				(hide yes)
			)
		)
		(property "Value" "+1V8"
			(at 119.38 45.72 0)
			(effects
				(font
					(size 1.27 1.27)
					(thickness 0.15)
				)
			)
		)
		(property "Footprint" ""
			(at 134.62 57.15 0)
			(effects
				(font
					(size 1.27 1.27)
					(thickness 0.15)
				)
				(justify left bottom)
				(hide yes)
			)
		)
		(property "Datasheet" ""
			(at 134.62 59.69 0)
			(effects
				(font
					(size 1.27 1.27)
					(thickness 0.15)
				)
				(justify left bottom)
				(hide yes)
			)
		)
		(property "Description" ""
			(at 119.38 49.53 0)
			(effects
				(font
					(size 1.27 1.27)
				)
			)
		)
		(property "Author" "Antmicro"
			(at 134.62 57.15 0)
			(effects
				(font
					(size 1.27 1.27)
					(thickness 0.15)
				)
				(justify left bottom)
				(hide yes)
			)
		)
		(property "License" "Apache-2.0"
			(at 134.62 59.69 0)
			(effects
				(font
					(size 1.27 1.27)
					(thickness 0.15)
				)
				(justify left bottom)
				(hide yes)
			)
		)
		(pin "1"
		)
		(instances
			(project ""
				(path ""
					(reference "#PWR0165")
					(unit 1)
				)
			)
		)
	)
	(symbol
		(lib_id "antmicroCapacitors0402:C_4u7_0402")
		(at 265.43 40.64 270)
		(mirror x)
		(unit 1)
		(exclude_from_sim no)
		(in_bom yes)
		(on_board yes)
		(dnp no)
		(fields_autoplaced yes)
		(property "Reference" "C67"
			(at 262.89 36.8235 90)
			(effects
				(font
					(size 1.27 1.27)
					(thickness 0.15)
				)
				(justify right)
			)
		)
		(property "Value" "C_4u7_0402"
			(at 255.27 20.32 0)
			(effects
				(font
					(size 1.27 1.27)
					(thickness 0.15)
				)
				(justify left bottom)
				(hide yes)
			)
		)
		(property "Footprint" "antmicro-footprints:C_0402_1005Metric"
			(at 252.73 20.32 0)
			(effects
				(font
					(size 1.27 1.27)
					(thickness 0.15)
				)
				(justify left bottom)
				(hide yes)
			)
		)
		(property "Datasheet" "https://www.murata.com/products/productdetail?partno=GRM155R61A475MEAA%23"
			(at 250.19 20.32 0)
			(effects
				(font
					(size 1.27 1.27)
					(thickness 0.15)
				)
				(justify left bottom)
				(hide yes)
			)
		)
		(property "Description" ""
			(at 265.43 40.64 0)
			(effects
				(font
					(size 1.27 1.27)
				)
			)
		)
		(property "MPN" "GRM155R61A475MEAAD"
			(at 247.65 20.32 0)
			(effects
				(font
					(size 1.27 1.27)
					(thickness 0.15)
				)
				(justify left bottom)
				(hide yes)
			)
		)
		(property "Manufacturer" "Murata"
			(at 245.11 20.32 0)
			(effects
				(font
					(size 1.27 1.27)
					(thickness 0.15)
				)
				(justify left bottom)
				(hide yes)
			)
		)
		(property "License" "Apache-2.0"
			(at 242.57 20.32 0)
			(effects
				(font
					(size 1.27 1.27)
					(thickness 0.15)
				)
				(justify left bottom)
				(hide yes)
			)
		)
		(property "Author" "Antmicro"
			(at 240.03 20.32 0)
			(effects
				(font
					(size 1.27 1.27)
					(thickness 0.15)
				)
				(justify left bottom)
				(hide yes)
			)
		)
		(property "Val" "4u7"
			(at 262.89 39.3635 90)
			(effects
				(font
					(size 1.27 1.27)
					(thickness 0.15)
				)
				(justify right)
			)
		)
		(property "Voltage" ""
			(at 237.49 20.32 0)
			(effects
				(font
					(size 1.27 1.27)
				)
				(justify left bottom)
				(hide yes)
			)
		)
		(property "Dielectric" ""
			(at 234.95 20.32 0)
			(effects
				(font
					(size 1.27 1.27)
				)
				(justify left bottom)
				(hide yes)
			)
		)
		(pin "1"
		)
		(pin "2"
		)
		(instances
			(project ""
				(path ""
					(reference "C67")
					(unit 1)
				)
			)
		)
	)
	(symbol
		(lib_id "antmicroCapacitors0402:C_4u7_0402")
		(at 256.54 73.66 90)
		(unit 1)
		(exclude_from_sim no)
		(in_bom yes)
		(on_board yes)
		(dnp no)
		(fields_autoplaced yes)
		(property "Reference" "C63"
			(at 259.08 69.8435 90)
			(effects
				(font
					(size 1.27 1.27)
					(thickness 0.15)
				)
				(justify right)
			)
		)
		(property "Value" "C_4u7_0402"
			(at 266.7 53.34 0)
			(effects
				(font
					(size 1.27 1.27)
					(thickness 0.15)
				)
				(justify left bottom)
				(hide yes)
			)
		)
		(property "Footprint" "antmicro-footprints:C_0402_1005Metric"
			(at 269.24 53.34 0)
			(effects
				(font
					(size 1.27 1.27)
					(thickness 0.15)
				)
				(justify left bottom)
				(hide yes)
			)
		)
		(property "Datasheet" "https://www.murata.com/products/productdetail?partno=GRM155R61A475MEAA%23"
			(at 271.78 53.34 0)
			(effects
				(font
					(size 1.27 1.27)
					(thickness 0.15)
				)
				(justify left bottom)
				(hide yes)
			)
		)
		(property "Description" ""
			(at 256.54 73.66 0)
			(effects
				(font
					(size 1.27 1.27)
				)
			)
		)
		(property "MPN" "GRM155R61A475MEAAD"
			(at 274.32 53.34 0)
			(effects
				(font
					(size 1.27 1.27)
					(thickness 0.15)
				)
				(justify left bottom)
				(hide yes)
			)
		)
		(property "Manufacturer" "Murata"
			(at 276.86 53.34 0)
			(effects
				(font
					(size 1.27 1.27)
					(thickness 0.15)
				)
				(justify left bottom)
				(hide yes)
			)
		)
		(property "License" "Apache-2.0"
			(at 279.4 53.34 0)
			(effects
				(font
					(size 1.27 1.27)
					(thickness 0.15)
				)
				(justify left bottom)
				(hide yes)
			)
		)
		(property "Author" "Antmicro"
			(at 281.94 53.34 0)
			(effects
				(font
					(size 1.27 1.27)
					(thickness 0.15)
				)
				(justify left bottom)
				(hide yes)
			)
		)
		(property "Val" "4u7"
			(at 259.08 72.3835 90)
			(effects
				(font
					(size 1.27 1.27)
					(thickness 0.15)
				)
				(justify right)
			)
		)
		(property "Voltage" ""
			(at 284.48 53.34 0)
			(effects
				(font
					(size 1.27 1.27)
				)
				(justify left bottom)
				(hide yes)
			)
		)
		(property "Dielectric" ""
			(at 287.02 53.34 0)
			(effects
				(font
					(size 1.27 1.27)
				)
				(justify left bottom)
				(hide yes)
			)
		)
		(pin "1"
		)
		(pin "2"
		)
		(instances
			(project ""
				(path ""
					(reference "C63")
					(unit 1)
				)
			)
		)
	)
	(symbol
		(lib_id "antmicropower:GND")
		(at 256.54 87.63 0)
		(unit 1)
		(exclude_from_sim no)
		(in_bom yes)
		(on_board yes)
		(dnp no)
		(property "Reference" "#PWR0191"
			(at 256.54 93.98 0)
			(effects
				(font
					(size 1.27 1.27)
				)
				(hide yes)
			)
		)
		(property "Value" "GND"
			(at 256.54 91.44 0)
			(effects
				(font
					(size 1.27 1.27)
				)
			)
		)
		(property "Footprint" ""
			(at 256.54 87.63 0)
			(effects
				(font
					(size 1.27 1.27)
				)
				(hide yes)
			)
		)
		(property "Datasheet" ""
			(at 256.54 87.63 0)
			(effects
				(font
					(size 1.27 1.27)
				)
				(hide yes)
			)
		)
		(property "Description" ""
			(at 256.54 87.63 0)
			(effects
				(font
					(size 1.27 1.27)
				)
			)
		)
		(pin "1"
		)
		(instances
			(project ""
				(path ""
					(reference "#PWR0191")
					(unit 1)
				)
			)
		)
	)
	(symbol
		(lib_id "antmicropower:GND")
		(at 114.3 87.63 0)
		(unit 1)
		(exclude_from_sim no)
		(in_bom yes)
		(on_board yes)
		(dnp no)
		(property "Reference" "#PWR0176"
			(at 114.3 93.98 0)
			(effects
				(font
					(size 1.27 1.27)
				)
				(hide yes)
			)
		)
		(property "Value" "GND"
			(at 114.3 91.44 0)
			(effects
				(font
					(size 1.27 1.27)
				)
			)
		)
		(property "Footprint" ""
			(at 114.3 87.63 0)
			(effects
				(font
					(size 1.27 1.27)
				)
				(hide yes)
			)
		)
		(property "Datasheet" ""
			(at 114.3 87.63 0)
			(effects
				(font
					(size 1.27 1.27)
				)
				(hide yes)
			)
		)
		(property "Description" ""
			(at 114.3 87.63 0)
			(effects
				(font
					(size 1.27 1.27)
				)
			)
		)
		(pin "1"
		)
		(instances
			(project ""
				(path ""
					(reference "#PWR0176")
					(unit 1)
				)
			)
		)
	)
	(symbol
		(lib_id "antmicroMemory:MT62F1G32D4DR-031")
		(at 179.07 53.34 0)
		(unit 1)
		(exclude_from_sim no)
		(in_bom yes)
		(on_board yes)
		(dnp no)
		(fields_autoplaced yes)
		(property "Reference" "U1"
			(at 196.215 45.72 0)
			(effects
				(font
					(size 1.27 1.27)
				)
			)
		)
		(property "Value" "MT62F1G32D4DR-031"
			(at 223.52 58.42 0)
			(effects
				(font
					(size 1.27 1.27)
				)
				(justify left bottom)
				(hide yes)
			)
		)
		(property "Footprint" "antmicro-footprints:BGA-315_12.4x15mm_Layout15x21_P0.8x0.7mm"
			(at 223.52 66.04 0)
			(effects
				(font
					(size 1.27 1.27)
				)
				(justify left bottom)
				(hide yes)
			)
		)
		(property "Datasheet" "https://www.micron.com/search-results?searchRequest=%7B%22term%22%3A%22MT62F1G32D4DR-031%22%7D"
			(at 223.52 63.5 0)
			(effects
				(font
					(size 1.27 1.27)
				)
				(justify left bottom)
				(hide yes)
			)
		)
		(property "Description" ""
			(at 179.07 53.34 0)
			(effects
				(font
					(size 1.27 1.27)
				)
			)
		)
		(property "Manufacturer" "Micron Technology"
			(at 223.52 60.96 0)
			(effects
				(font
					(size 1.27 1.27)
				)
				(justify left bottom)
				(hide yes)
			)
		)
		(property "MPN" "MT62F1G32D4DR-031 WT:B"
			(at 196.215 48.26 0)
			(effects
				(font
					(size 1.27 1.27)
				)
			)
		)
		(property "Author" "Antmicro"
			(at 223.52 68.58 0)
			(effects
				(font
					(size 1.27 1.27)
				)
				(justify left bottom)
				(hide yes)
			)
		)
		(property "License" "Apache-2.0"
			(at 223.52 71.12 0)
			(effects
				(font
					(size 1.27 1.27)
				)
				(justify left bottom)
				(hide yes)
			)
		)
		(pin "A1"
		)
		(pin "A10"
		)
		(pin "A11"
		)
		(pin "A13"
		)
		(pin "A14"
		)
		(pin "A15"
		)
		(pin "A2"
		)
		(pin "A3"
		)
		(pin "A5"
		)
		(pin "A6"
		)
		(pin "A7"
		)
		(pin "A8"
		)
		(pin "A9"
		)
		(pin "AA1"
		)
		(pin "AA10"
		)
		(pin "AA11"
		)
		(pin "AA13"
		)
		(pin "AA14"
		)
		(pin "AA15"
		)
		(pin "AA2"
		)
		(pin "AA3"
		)
		(pin "AA5"
		)
		(pin "AA6"
		)
		(pin "AA7"
		)
		(pin "AA8"
		)
		(pin "AA9"
		)
		(pin "B1"
		)
		(pin "B10"
		)
		(pin "B12"
		)
		(pin "B14"
		)
		(pin "B15"
		)
		(pin "B2"
		)
		(pin "B4"
		)
		(pin "B6"
		)
		(pin "B7"
		)
		(pin "B8"
		)
		(pin "B9"
		)
		(pin "C1"
		)
		(pin "C11"
		)
		(pin "C13"
		)
		(pin "C15"
		)
		(pin "C3"
		)
		(pin "C5"
		)
		(pin "C7"
		)
		(pin "C8"
		)
		(pin "C9"
		)
		(pin "D10"
		)
		(pin "D12"
		)
		(pin "D14"
		)
		(pin "D2"
		)
		(pin "D4"
		)
		(pin "D6"
		)
		(pin "D7"
		)
		(pin "D8"
		)
		(pin "D9"
		)
		(pin "E1"
		)
		(pin "E11"
		)
		(pin "E13"
		)
		(pin "E15"
		)
		(pin "E3"
		)
		(pin "E5"
		)
		(pin "E7"
		)
		(pin "E8"
		)
		(pin "E9"
		)
		(pin "F1"
		)
		(pin "F10"
		)
		(pin "F12"
		)
		(pin "F13"
		)
		(pin "F14"
		)
		(pin "F15"
		)
		(pin "F2"
		)
		(pin "F3"
		)
		(pin "F4"
		)
		(pin "F6"
		)
		(pin "F7"
		)
		(pin "F8"
		)
		(pin "F9"
		)
		(pin "G1"
		)
		(pin "G11"
		)
		(pin "G13"
		)
		(pin "G14"
		)
		(pin "G15"
		)
		(pin "G2"
		)
		(pin "G3"
		)
		(pin "G5"
		)
		(pin "G7"
		)
		(pin "G9"
		)
		(pin "H1"
		)
		(pin "H10"
		)
		(pin "H12"
		)
		(pin "H14"
		)
		(pin "H15"
		)
		(pin "H2"
		)
		(pin "H3"
		)
		(pin "H4"
		)
		(pin "H6"
		)
		(pin "H8"
		)
		(pin "J1"
		)
		(pin "J10"
		)
		(pin "J11"
		)
		(pin "J12"
		)
		(pin "J13"
		)
		(pin "J14"
		)
		(pin "J15"
		)
		(pin "J2"
		)
		(pin "J3"
		)
		(pin "J4"
		)
		(pin "J5"
		)
		(pin "J6"
		)
		(pin "J7"
		)
		(pin "J8"
		)
		(pin "K1"
		)
		(pin "K10"
		)
		(pin "K11"
		)
		(pin "K12"
		)
		(pin "K13"
		)
		(pin "K14"
		)
		(pin "K15"
		)
		(pin "K2"
		)
		(pin "K3"
		)
		(pin "K4"
		)
		(pin "K5"
		)
		(pin "K6"
		)
		(pin "K7"
		)
		(pin "K8"
		)
		(pin "K9"
		)
		(pin "L1"
		)
		(pin "L10"
		)
		(pin "L11"
		)
		(pin "L12"
		)
		(pin "L13"
		)
		(pin "L14"
		)
		(pin "L15"
		)
		(pin "L2"
		)
		(pin "L3"
		)
		(pin "L4"
		)
		(pin "L5"
		)
		(pin "L6"
		)
		(pin "L7"
		)
		(pin "L8"
		)
		(pin "L9"
		)
		(pin "M1"
		)
		(pin "M10"
		)
		(pin "M11"
		)
		(pin "M12"
		)
		(pin "M13"
		)
		(pin "M14"
		)
		(pin "M15"
		)
		(pin "M2"
		)
		(pin "M3"
		)
		(pin "M4"
		)
		(pin "M5"
		)
		(pin "M6"
		)
		(pin "M7"
		)
		(pin "M8"
		)
		(pin "M9"
		)
		(pin "N1"
		)
		(pin "N10"
		)
		(pin "N11"
		)
		(pin "N12"
		)
		(pin "N13"
		)
		(pin "N14"
		)
		(pin "N15"
		)
		(pin "N2"
		)
		(pin "N3"
		)
		(pin "N4"
		)
		(pin "N5"
		)
		(pin "N6"
		)
		(pin "N8"
		)
		(pin "N9"
		)
		(pin "P1"
		)
		(pin "P10"
		)
		(pin "P12"
		)
		(pin "P13"
		)
		(pin "P14"
		)
		(pin "P15"
		)
		(pin "P2"
		)
		(pin "P4"
		)
		(pin "P6"
		)
		(pin "P8"
		)
		(pin "R1"
		)
		(pin "R11"
		)
		(pin "R13"
		)
		(pin "R14"
		)
		(pin "R15"
		)
		(pin "R2"
		)
		(pin "R3"
		)
		(pin "R5"
		)
		(pin "R7"
		)
		(pin "R9"
		)
		(pin "T1"
		)
		(pin "T10"
		)
		(pin "T12"
		)
		(pin "T13"
		)
		(pin "T14"
		)
		(pin "T15"
		)
		(pin "T2"
		)
		(pin "T3"
		)
		(pin "T4"
		)
		(pin "T6"
		)
		(pin "T7"
		)
		(pin "T8"
		)
		(pin "T9"
		)
		(pin "U1"
		)
		(pin "U11"
		)
		(pin "U13"
		)
		(pin "U15"
		)
		(pin "U3"
		)
		(pin "U5"
		)
		(pin "U7"
		)
		(pin "U8"
		)
		(pin "U9"
		)
		(pin "V10"
		)
		(pin "V12"
		)
		(pin "V14"
		)
		(pin "V2"
		)
		(pin "V4"
		)
		(pin "V6"
		)
		(pin "V7"
		)
		(pin "V8"
		)
		(pin "V9"
		)
		(pin "W1"
		)
		(pin "W11"
		)
		(pin "W13"
		)
		(pin "W15"
		)
		(pin "W3"
		)
		(pin "W5"
		)
		(pin "W7"
		)
		(pin "W8"
		)
		(pin "W9"
		)
		(pin "Y1"
		)
		(pin "Y10"
		)
		(pin "Y12"
		)
		(pin "Y14"
		)
		(pin "Y15"
		)
		(pin "Y2"
		)
		(pin "Y4"
		)
		(pin "Y6"
		)
		(pin "Y7"
		)
		(pin "Y8"
		)
		(pin "Y9"
		)
		(pin "A12"
		)
		(pin "A4"
		)
		(pin "B11"
		)
		(pin "B13"
		)
		(pin "B3"
		)
		(pin "B5"
		)
		(pin "C10"
		)
		(pin "C12"
		)
		(pin "C14"
		)
		(pin "C2"
		)
		(pin "C4"
		)
		(pin "C6"
		)
		(pin "D1"
		)
		(pin "D11"
		)
		(pin "D13"
		)
		(pin "D15"
		)
		(pin "D3"
		)
		(pin "D5"
		)
		(pin "E10"
		)
		(pin "E12"
		)
		(pin "E14"
		)
		(pin "E2"
		)
		(pin "E4"
		)
		(pin "E6"
		)
		(pin "F11"
		)
		(pin "F5"
		)
		(pin "G10"
		)
		(pin "G12"
		)
		(pin "G4"
		)
		(pin "G6"
		)
		(pin "G8"
		)
		(pin "H11"
		)
		(pin "H13"
		)
		(pin "H5"
		)
		(pin "H7"
		)
		(pin "H9"
		)
		(pin "J9"
		)
		(pin "AA12"
		)
		(pin "AA4"
		)
		(pin "N7"
		)
		(pin "P11"
		)
		(pin "P3"
		)
		(pin "P5"
		)
		(pin "P7"
		)
		(pin "P9"
		)
		(pin "R10"
		)
		(pin "R12"
		)
		(pin "R4"
		)
		(pin "R6"
		)
		(pin "R8"
		)
		(pin "T11"
		)
		(pin "T5"
		)
		(pin "U10"
		)
		(pin "U12"
		)
		(pin "U14"
		)
		(pin "U2"
		)
		(pin "U4"
		)
		(pin "U6"
		)
		(pin "V1"
		)
		(pin "V11"
		)
		(pin "V13"
		)
		(pin "V15"
		)
		(pin "V3"
		)
		(pin "V5"
		)
		(pin "W10"
		)
		(pin "W12"
		)
		(pin "W14"
		)
		(pin "W2"
		)
		(pin "W4"
		)
		(pin "W6"
		)
		(pin "Y11"
		)
		(pin "Y13"
		)
		(pin "Y3"
		)
		(pin "Y5"
		)
		(instances
			(project ""
				(path ""
					(reference "U1")
					(unit 1)
				)
			)
		)
	)
	(symbol
		(lib_id "antmicroCapacitors0402:C_4u7_0402")
		(at 247.65 87.63 90)
		(unit 1)
		(exclude_from_sim no)
		(in_bom yes)
		(on_board yes)
		(dnp no)
		(fields_autoplaced yes)
		(property "Reference" "C60"
			(at 250.19 83.8135 90)
			(effects
				(font
					(size 1.27 1.27)
					(thickness 0.15)
				)
				(justify right)
			)
		)
		(property "Value" "C_4u7_0402"
			(at 257.81 67.31 0)
			(effects
				(font
					(size 1.27 1.27)
					(thickness 0.15)
				)
				(justify left bottom)
				(hide yes)
			)
		)
		(property "Footprint" "antmicro-footprints:C_0402_1005Metric"
			(at 260.35 67.31 0)
			(effects
				(font
					(size 1.27 1.27)
					(thickness 0.15)
				)
				(justify left bottom)
				(hide yes)
			)
		)
		(property "Datasheet" "https://www.murata.com/products/productdetail?partno=GRM155R61A475MEAA%23"
			(at 262.89 67.31 0)
			(effects
				(font
					(size 1.27 1.27)
					(thickness 0.15)
				)
				(justify left bottom)
				(hide yes)
			)
		)
		(property "Description" ""
			(at 247.65 87.63 0)
			(effects
				(font
					(size 1.27 1.27)
				)
			)
		)
		(property "MPN" "GRM155R61A475MEAAD"
			(at 265.43 67.31 0)
			(effects
				(font
					(size 1.27 1.27)
					(thickness 0.15)
				)
				(justify left bottom)
				(hide yes)
			)
		)
		(property "Manufacturer" "Murata"
			(at 267.97 67.31 0)
			(effects
				(font
					(size 1.27 1.27)
					(thickness 0.15)
				)
				(justify left bottom)
				(hide yes)
			)
		)
		(property "License" "Apache-2.0"
			(at 270.51 67.31 0)
			(effects
				(font
					(size 1.27 1.27)
					(thickness 0.15)
				)
				(justify left bottom)
				(hide yes)
			)
		)
		(property "Author" "Antmicro"
			(at 273.05 67.31 0)
			(effects
				(font
					(size 1.27 1.27)
					(thickness 0.15)
				)
				(justify left bottom)
				(hide yes)
			)
		)
		(property "Val" "4u7"
			(at 250.19 86.3535 90)
			(effects
				(font
					(size 1.27 1.27)
					(thickness 0.15)
				)
				(justify right)
			)
		)
		(property "Voltage" ""
			(at 275.59 67.31 0)
			(effects
				(font
					(size 1.27 1.27)
				)
				(justify left bottom)
				(hide yes)
			)
		)
		(property "Dielectric" ""
			(at 278.13 67.31 0)
			(effects
				(font
					(size 1.27 1.27)
				)
				(justify left bottom)
				(hide yes)
			)
		)
		(pin "1"
		)
		(pin "2"
		)
		(instances
			(project ""
				(path ""
					(reference "C60")
					(unit 1)
				)
			)
		)
	)
	(symbol
		(lib_id "antmicroCapacitors0402:C_4u7_0402")
		(at 123.19 73.66 90)
		(unit 1)
		(exclude_from_sim no)
		(in_bom yes)
		(on_board yes)
		(dnp no)
		(fields_autoplaced yes)
		(property "Reference" "C42"
			(at 125.73 69.8435 90)
			(effects
				(font
					(size 1.27 1.27)
					(thickness 0.15)
				)
				(justify right)
			)
		)
		(property "Value" "C_4u7_0402"
			(at 133.35 53.34 0)
			(effects
				(font
					(size 1.27 1.27)
					(thickness 0.15)
				)
				(justify left bottom)
				(hide yes)
			)
		)
		(property "Footprint" "antmicro-footprints:C_0402_1005Metric"
			(at 135.89 53.34 0)
			(effects
				(font
					(size 1.27 1.27)
					(thickness 0.15)
				)
				(justify left bottom)
				(hide yes)
			)
		)
		(property "Datasheet" "https://www.murata.com/products/productdetail?partno=GRM155R61A475MEAA%23"
			(at 138.43 53.34 0)
			(effects
				(font
					(size 1.27 1.27)
					(thickness 0.15)
				)
				(justify left bottom)
				(hide yes)
			)
		)
		(property "Description" ""
			(at 123.19 73.66 0)
			(effects
				(font
					(size 1.27 1.27)
				)
			)
		)
		(property "MPN" "GRM155R61A475MEAAD"
			(at 140.97 53.34 0)
			(effects
				(font
					(size 1.27 1.27)
					(thickness 0.15)
				)
				(justify left bottom)
				(hide yes)
			)
		)
		(property "Manufacturer" "Murata"
			(at 143.51 53.34 0)
			(effects
				(font
					(size 1.27 1.27)
					(thickness 0.15)
				)
				(justify left bottom)
				(hide yes)
			)
		)
		(property "License" "Apache-2.0"
			(at 146.05 53.34 0)
			(effects
				(font
					(size 1.27 1.27)
					(thickness 0.15)
				)
				(justify left bottom)
				(hide yes)
			)
		)
		(property "Author" "Antmicro"
			(at 148.59 53.34 0)
			(effects
				(font
					(size 1.27 1.27)
					(thickness 0.15)
				)
				(justify left bottom)
				(hide yes)
			)
		)
		(property "Val" "4u7"
			(at 125.73 72.3835 90)
			(effects
				(font
					(size 1.27 1.27)
					(thickness 0.15)
				)
				(justify right)
			)
		)
		(property "Voltage" ""
			(at 151.13 53.34 0)
			(effects
				(font
					(size 1.27 1.27)
				)
				(justify left bottom)
				(hide yes)
			)
		)
		(property "Dielectric" ""
			(at 153.67 53.34 0)
			(effects
				(font
					(size 1.27 1.27)
				)
				(justify left bottom)
				(hide yes)
			)
		)
		(pin "1"
		)
		(pin "2"
		)
		(instances
			(project ""
				(path ""
					(reference "C42")
					(unit 1)
				)
			)
		)
	)
	(symbol
		(lib_id "antmicroCapacitors0402:C_4u7_0402")
		(at 229.87 54.61 270)
		(mirror x)
		(unit 1)
		(exclude_from_sim no)
		(in_bom yes)
		(on_board yes)
		(dnp no)
		(fields_autoplaced yes)
		(property "Reference" "C54"
			(at 227.33 50.7935 90)
			(effects
				(font
					(size 1.27 1.27)
					(thickness 0.15)
				)
				(justify right)
			)
		)
		(property "Value" "C_4u7_0402"
			(at 219.71 34.29 0)
			(effects
				(font
					(size 1.27 1.27)
					(thickness 0.15)
				)
				(justify left bottom)
				(hide yes)
			)
		)
		(property "Footprint" "antmicro-footprints:C_0402_1005Metric"
			(at 217.17 34.29 0)
			(effects
				(font
					(size 1.27 1.27)
					(thickness 0.15)
				)
				(justify left bottom)
				(hide yes)
			)
		)
		(property "Datasheet" "https://www.murata.com/products/productdetail?partno=GRM155R61A475MEAA%23"
			(at 214.63 34.29 0)
			(effects
				(font
					(size 1.27 1.27)
					(thickness 0.15)
				)
				(justify left bottom)
				(hide yes)
			)
		)
		(property "Description" ""
			(at 229.87 54.61 0)
			(effects
				(font
					(size 1.27 1.27)
				)
			)
		)
		(property "MPN" "GRM155R61A475MEAAD"
			(at 212.09 34.29 0)
			(effects
				(font
					(size 1.27 1.27)
					(thickness 0.15)
				)
				(justify left bottom)
				(hide yes)
			)
		)
		(property "Manufacturer" "Murata"
			(at 209.55 34.29 0)
			(effects
				(font
					(size 1.27 1.27)
					(thickness 0.15)
				)
				(justify left bottom)
				(hide yes)
			)
		)
		(property "License" "Apache-2.0"
			(at 207.01 34.29 0)
			(effects
				(font
					(size 1.27 1.27)
					(thickness 0.15)
				)
				(justify left bottom)
				(hide yes)
			)
		)
		(property "Author" "Antmicro"
			(at 204.47 34.29 0)
			(effects
				(font
					(size 1.27 1.27)
					(thickness 0.15)
				)
				(justify left bottom)
				(hide yes)
			)
		)
		(property "Val" "4u7"
			(at 227.33 53.3335 90)
			(effects
				(font
					(size 1.27 1.27)
					(thickness 0.15)
				)
				(justify right)
			)
		)
		(property "Voltage" ""
			(at 201.93 34.29 0)
			(effects
				(font
					(size 1.27 1.27)
				)
				(justify left bottom)
				(hide yes)
			)
		)
		(property "Dielectric" ""
			(at 199.39 34.29 0)
			(effects
				(font
					(size 1.27 1.27)
				)
				(justify left bottom)
				(hide yes)
			)
		)
		(pin "1"
		)
		(pin "2"
		)
		(instances
			(project ""
				(path ""
					(reference "C54")
					(unit 1)
				)
			)
		)
	)
	(symbol
		(lib_id "antmicroCapacitors0402:C_4u7_0402")
		(at 140.97 73.66 90)
		(unit 1)
		(exclude_from_sim no)
		(in_bom yes)
		(on_board yes)
		(dnp no)
		(fields_autoplaced yes)
		(property "Reference" "C47"
			(at 143.51 69.8435 90)
			(effects
				(font
					(size 1.27 1.27)
					(thickness 0.15)
				)
				(justify right)
			)
		)
		(property "Value" "C_4u7_0402"
			(at 151.13 53.34 0)
			(effects
				(font
					(size 1.27 1.27)
					(thickness 0.15)
				)
				(justify left bottom)
				(hide yes)
			)
		)
		(property "Footprint" "antmicro-footprints:C_0402_1005Metric"
			(at 153.67 53.34 0)
			(effects
				(font
					(size 1.27 1.27)
					(thickness 0.15)
				)
				(justify left bottom)
				(hide yes)
			)
		)
		(property "Datasheet" "https://www.murata.com/products/productdetail?partno=GRM155R61A475MEAA%23"
			(at 156.21 53.34 0)
			(effects
				(font
					(size 1.27 1.27)
					(thickness 0.15)
				)
				(justify left bottom)
				(hide yes)
			)
		)
		(property "Description" ""
			(at 140.97 73.66 0)
			(effects
				(font
					(size 1.27 1.27)
				)
			)
		)
		(property "MPN" "GRM155R61A475MEAAD"
			(at 158.75 53.34 0)
			(effects
				(font
					(size 1.27 1.27)
					(thickness 0.15)
				)
				(justify left bottom)
				(hide yes)
			)
		)
		(property "Manufacturer" "Murata"
			(at 161.29 53.34 0)
			(effects
				(font
					(size 1.27 1.27)
					(thickness 0.15)
				)
				(justify left bottom)
				(hide yes)
			)
		)
		(property "License" "Apache-2.0"
			(at 163.83 53.34 0)
			(effects
				(font
					(size 1.27 1.27)
					(thickness 0.15)
				)
				(justify left bottom)
				(hide yes)
			)
		)
		(property "Author" "Antmicro"
			(at 166.37 53.34 0)
			(effects
				(font
					(size 1.27 1.27)
					(thickness 0.15)
				)
				(justify left bottom)
				(hide yes)
			)
		)
		(property "Val" "4u7"
			(at 143.51 72.3835 90)
			(effects
				(font
					(size 1.27 1.27)
					(thickness 0.15)
				)
				(justify right)
			)
		)
		(property "Voltage" ""
			(at 168.91 53.34 0)
			(effects
				(font
					(size 1.27 1.27)
				)
				(justify left bottom)
				(hide yes)
			)
		)
		(property "Dielectric" ""
			(at 171.45 53.34 0)
			(effects
				(font
					(size 1.27 1.27)
				)
				(justify left bottom)
				(hide yes)
			)
		)
		(pin "1"
		)
		(pin "2"
		)
		(instances
			(project ""
				(path ""
					(reference "C47")
					(unit 1)
				)
			)
		)
	)
	(symbol
		(lib_id "antmicroCapacitors0402:C_4u7_0402")
		(at 265.43 54.61 270)
		(mirror x)
		(unit 1)
		(exclude_from_sim no)
		(in_bom yes)
		(on_board yes)
		(dnp no)
		(fields_autoplaced yes)
		(property "Reference" "C68"
			(at 262.89 50.7935 90)
			(effects
				(font
					(size 1.27 1.27)
					(thickness 0.15)
				)
				(justify right)
			)
		)
		(property "Value" "C_4u7_0402"
			(at 255.27 34.29 0)
			(effects
				(font
					(size 1.27 1.27)
					(thickness 0.15)
				)
				(justify left bottom)
				(hide yes)
			)
		)
		(property "Footprint" "antmicro-footprints:C_0402_1005Metric"
			(at 252.73 34.29 0)
			(effects
				(font
					(size 1.27 1.27)
					(thickness 0.15)
				)
				(justify left bottom)
				(hide yes)
			)
		)
		(property "Datasheet" "https://www.murata.com/products/productdetail?partno=GRM155R61A475MEAA%23"
			(at 250.19 34.29 0)
			(effects
				(font
					(size 1.27 1.27)
					(thickness 0.15)
				)
				(justify left bottom)
				(hide yes)
			)
		)
		(property "Description" ""
			(at 265.43 54.61 0)
			(effects
				(font
					(size 1.27 1.27)
				)
			)
		)
		(property "MPN" "GRM155R61A475MEAAD"
			(at 247.65 34.29 0)
			(effects
				(font
					(size 1.27 1.27)
					(thickness 0.15)
				)
				(justify left bottom)
				(hide yes)
			)
		)
		(property "Manufacturer" "Murata"
			(at 245.11 34.29 0)
			(effects
				(font
					(size 1.27 1.27)
					(thickness 0.15)
				)
				(justify left bottom)
				(hide yes)
			)
		)
		(property "License" "Apache-2.0"
			(at 242.57 34.29 0)
			(effects
				(font
					(size 1.27 1.27)
					(thickness 0.15)
				)
				(justify left bottom)
				(hide yes)
			)
		)
		(property "Author" "Antmicro"
			(at 240.03 34.29 0)
			(effects
				(font
					(size 1.27 1.27)
					(thickness 0.15)
				)
				(justify left bottom)
				(hide yes)
			)
		)
		(property "Val" "4u7"
			(at 262.89 53.3335 90)
			(effects
				(font
					(size 1.27 1.27)
					(thickness 0.15)
				)
				(justify right)
			)
		)
		(property "Voltage" ""
			(at 237.49 34.29 0)
			(effects
				(font
					(size 1.27 1.27)
				)
				(justify left bottom)
				(hide yes)
			)
		)
		(property "Dielectric" ""
			(at 234.95 34.29 0)
			(effects
				(font
					(size 1.27 1.27)
				)
				(justify left bottom)
				(hide yes)
			)
		)
		(pin "1"
		)
		(pin "2"
		)
		(instances
			(project ""
				(path ""
					(reference "C68")
					(unit 1)
				)
			)
		)
	)
	(symbol
		(lib_id "antmicropower:GND")
		(at 170.18 83.82 0)
		(unit 1)
		(exclude_from_sim no)
		(in_bom yes)
		(on_board yes)
		(dnp no)
		(property "Reference" "#PWR0164"
			(at 170.18 90.17 0)
			(effects
				(font
					(size 1.27 1.27)
				)
				(hide yes)
			)
		)
		(property "Value" "GND"
			(at 170.307 88.2142 0)
			(effects
				(font
					(size 1.27 1.27)
				)
			)
		)
		(property "Footprint" ""
			(at 170.18 83.82 0)
			(effects
				(font
					(size 1.27 1.27)
				)
				(hide yes)
			)
		)
		(property "Datasheet" ""
			(at 170.18 83.82 0)
			(effects
				(font
					(size 1.27 1.27)
				)
				(hide yes)
			)
		)
		(property "Description" ""
			(at 170.18 83.82 0)
			(effects
				(font
					(size 1.27 1.27)
				)
			)
		)
		(pin "1"
		)
		(instances
			(project ""
				(path ""
					(reference "#PWR0164")
					(unit 1)
				)
			)
		)
	)
	(symbol
		(lib_id "antmicropower:GND")
		(at 247.65 87.63 0)
		(unit 1)
		(exclude_from_sim no)
		(in_bom yes)
		(on_board yes)
		(dnp no)
		(property "Reference" "#PWR0192"
			(at 247.65 93.98 0)
			(effects
				(font
					(size 1.27 1.27)
				)
				(hide yes)
			)
		)
		(property "Value" "GND"
			(at 247.65 91.44 0)
			(effects
				(font
					(size 1.27 1.27)
				)
			)
		)
		(property "Footprint" ""
			(at 247.65 87.63 0)
			(effects
				(font
					(size 1.27 1.27)
				)
				(hide yes)
			)
		)
		(property "Datasheet" ""
			(at 247.65 87.63 0)
			(effects
				(font
					(size 1.27 1.27)
				)
				(hide yes)
			)
		)
		(property "Description" ""
			(at 247.65 87.63 0)
			(effects
				(font
					(size 1.27 1.27)
				)
			)
		)
		(pin "1"
		)
		(instances
			(project ""
				(path ""
					(reference "#PWR0192")
					(unit 1)
				)
			)
		)
	)
	(symbol
		(lib_id "antmicropower:GND")
		(at 256.54 54.61 0)
		(mirror y)
		(unit 1)
		(exclude_from_sim no)
		(in_bom yes)
		(on_board yes)
		(dnp no)
		(property "Reference" "#PWR0198"
			(at 256.54 60.96 0)
			(effects
				(font
					(size 1.27 1.27)
				)
				(hide yes)
			)
		)
		(property "Value" "GND"
			(at 256.54 58.42 0)
			(effects
				(font
					(size 1.27 1.27)
				)
			)
		)
		(property "Footprint" ""
			(at 256.54 54.61 0)
			(effects
				(font
					(size 1.27 1.27)
				)
				(hide yes)
			)
		)
		(property "Datasheet" ""
			(at 256.54 54.61 0)
			(effects
				(font
					(size 1.27 1.27)
				)
				(hide yes)
			)
		)
		(property "Description" ""
			(at 256.54 54.61 0)
			(effects
				(font
					(size 1.27 1.27)
				)
			)
		)
		(pin "1"
		)
		(instances
			(project ""
				(path ""
					(reference "#PWR0198")
					(unit 1)
				)
			)
		)
	)
	(symbol
		(lib_id "antmicropower:GND")
		(at 149.86 87.63 0)
		(unit 1)
		(exclude_from_sim no)
		(in_bom yes)
		(on_board yes)
		(dnp no)
		(property "Reference" "#PWR0168"
			(at 149.86 93.98 0)
			(effects
				(font
					(size 1.27 1.27)
				)
				(hide yes)
			)
		)
		(property "Value" "GND"
			(at 149.86 91.44 0)
			(effects
				(font
					(size 1.27 1.27)
				)
			)
		)
		(property "Footprint" ""
			(at 149.86 87.63 0)
			(effects
				(font
					(size 1.27 1.27)
				)
				(hide yes)
			)
		)
		(property "Datasheet" ""
			(at 149.86 87.63 0)
			(effects
				(font
					(size 1.27 1.27)
				)
				(hide yes)
			)
		)
		(property "Description" ""
			(at 149.86 87.63 0)
			(effects
				(font
					(size 1.27 1.27)
				)
			)
		)
		(pin "1"
		)
		(instances
			(project ""
				(path ""
					(reference "#PWR0168")
					(unit 1)
				)
			)
		)
	)
	(symbol
		(lib_id "antmicroCapacitors0402:C_4u7_0402")
		(at 256.54 40.64 270)
		(mirror x)
		(unit 1)
		(exclude_from_sim no)
		(in_bom yes)
		(on_board yes)
		(dnp no)
		(fields_autoplaced yes)
		(property "Reference" "C65"
			(at 254 36.8235 90)
			(effects
				(font
					(size 1.27 1.27)
					(thickness 0.15)
				)
				(justify right)
			)
		)
		(property "Value" "C_4u7_0402"
			(at 246.38 20.32 0)
			(effects
				(font
					(size 1.27 1.27)
					(thickness 0.15)
				)
				(justify left bottom)
				(hide yes)
			)
		)
		(property "Footprint" "antmicro-footprints:C_0402_1005Metric"
			(at 243.84 20.32 0)
			(effects
				(font
					(size 1.27 1.27)
					(thickness 0.15)
				)
				(justify left bottom)
				(hide yes)
			)
		)
		(property "Datasheet" "https://www.murata.com/products/productdetail?partno=GRM155R61A475MEAA%23"
			(at 241.3 20.32 0)
			(effects
				(font
					(size 1.27 1.27)
					(thickness 0.15)
				)
				(justify left bottom)
				(hide yes)
			)
		)
		(property "Description" ""
			(at 256.54 40.64 0)
			(effects
				(font
					(size 1.27 1.27)
				)
			)
		)
		(property "MPN" "GRM155R61A475MEAAD"
			(at 238.76 20.32 0)
			(effects
				(font
					(size 1.27 1.27)
					(thickness 0.15)
				)
				(justify left bottom)
				(hide yes)
			)
		)
		(property "Manufacturer" "Murata"
			(at 236.22 20.32 0)
			(effects
				(font
					(size 1.27 1.27)
					(thickness 0.15)
				)
				(justify left bottom)
				(hide yes)
			)
		)
		(property "License" "Apache-2.0"
			(at 233.68 20.32 0)
			(effects
				(font
					(size 1.27 1.27)
					(thickness 0.15)
				)
				(justify left bottom)
				(hide yes)
			)
		)
		(property "Author" "Antmicro"
			(at 231.14 20.32 0)
			(effects
				(font
					(size 1.27 1.27)
					(thickness 0.15)
				)
				(justify left bottom)
				(hide yes)
			)
		)
		(property "Val" "4u7"
			(at 254 39.3635 90)
			(effects
				(font
					(size 1.27 1.27)
					(thickness 0.15)
				)
				(justify right)
			)
		)
		(property "Voltage" ""
			(at 228.6 20.32 0)
			(effects
				(font
					(size 1.27 1.27)
				)
				(justify left bottom)
				(hide yes)
			)
		)
		(property "Dielectric" ""
			(at 226.06 20.32 0)
			(effects
				(font
					(size 1.27 1.27)
				)
				(justify left bottom)
				(hide yes)
			)
		)
		(pin "1"
		)
		(pin "2"
		)
		(instances
			(project ""
				(path ""
					(reference "C65")
					(unit 1)
				)
			)
		)
	)
	(symbol
		(lib_id "antmicroCapacitors0402:C_4u7_0402")
		(at 149.86 87.63 90)
		(unit 1)
		(exclude_from_sim no)
		(in_bom yes)
		(on_board yes)
		(dnp no)
		(fields_autoplaced yes)
		(property "Reference" "C50"
			(at 152.4 83.8135 90)
			(effects
				(font
					(size 1.27 1.27)
					(thickness 0.15)
				)
				(justify right)
			)
		)
		(property "Value" "C_4u7_0402"
			(at 160.02 67.31 0)
			(effects
				(font
					(size 1.27 1.27)
					(thickness 0.15)
				)
				(justify left bottom)
				(hide yes)
			)
		)
		(property "Footprint" "antmicro-footprints:C_0402_1005Metric"
			(at 162.56 67.31 0)
			(effects
				(font
					(size 1.27 1.27)
					(thickness 0.15)
				)
				(justify left bottom)
				(hide yes)
			)
		)
		(property "Datasheet" "https://www.murata.com/products/productdetail?partno=GRM155R61A475MEAA%23"
			(at 165.1 67.31 0)
			(effects
				(font
					(size 1.27 1.27)
					(thickness 0.15)
				)
				(justify left bottom)
				(hide yes)
			)
		)
		(property "Description" ""
			(at 149.86 87.63 0)
			(effects
				(font
					(size 1.27 1.27)
				)
			)
		)
		(property "MPN" "GRM155R61A475MEAAD"
			(at 167.64 67.31 0)
			(effects
				(font
					(size 1.27 1.27)
					(thickness 0.15)
				)
				(justify left bottom)
				(hide yes)
			)
		)
		(property "Manufacturer" "Murata"
			(at 170.18 67.31 0)
			(effects
				(font
					(size 1.27 1.27)
					(thickness 0.15)
				)
				(justify left bottom)
				(hide yes)
			)
		)
		(property "License" "Apache-2.0"
			(at 172.72 67.31 0)
			(effects
				(font
					(size 1.27 1.27)
					(thickness 0.15)
				)
				(justify left bottom)
				(hide yes)
			)
		)
		(property "Author" "Antmicro"
			(at 175.26 67.31 0)
			(effects
				(font
					(size 1.27 1.27)
					(thickness 0.15)
				)
				(justify left bottom)
				(hide yes)
			)
		)
		(property "Val" "4u7"
			(at 152.4 86.3535 90)
			(effects
				(font
					(size 1.27 1.27)
					(thickness 0.15)
				)
				(justify right)
			)
		)
		(property "Voltage" ""
			(at 177.8 67.31 0)
			(effects
				(font
					(size 1.27 1.27)
				)
				(justify left bottom)
				(hide yes)
			)
		)
		(property "Dielectric" ""
			(at 180.34 67.31 0)
			(effects
				(font
					(size 1.27 1.27)
				)
				(justify left bottom)
				(hide yes)
			)
		)
		(pin "1"
		)
		(pin "2"
		)
		(instances
			(project ""
				(path ""
					(reference "C50")
					(unit 1)
				)
			)
		)
	)
	(symbol
		(lib_id "antmicroCapacitors0402:C_4u7_0402")
		(at 256.54 54.61 270)
		(mirror x)
		(unit 1)
		(exclude_from_sim no)
		(in_bom yes)
		(on_board yes)
		(dnp no)
		(fields_autoplaced yes)
		(property "Reference" "C66"
			(at 254 50.7935 90)
			(effects
				(font
					(size 1.27 1.27)
					(thickness 0.15)
				)
				(justify right)
			)
		)
		(property "Value" "C_4u7_0402"
			(at 246.38 34.29 0)
			(effects
				(font
					(size 1.27 1.27)
					(thickness 0.15)
				)
				(justify left bottom)
				(hide yes)
			)
		)
		(property "Footprint" "antmicro-footprints:C_0402_1005Metric"
			(at 243.84 34.29 0)
			(effects
				(font
					(size 1.27 1.27)
					(thickness 0.15)
				)
				(justify left bottom)
				(hide yes)
			)
		)
		(property "Datasheet" "https://www.murata.com/products/productdetail?partno=GRM155R61A475MEAA%23"
			(at 241.3 34.29 0)
			(effects
				(font
					(size 1.27 1.27)
					(thickness 0.15)
				)
				(justify left bottom)
				(hide yes)
			)
		)
		(property "Description" ""
			(at 256.54 54.61 0)
			(effects
				(font
					(size 1.27 1.27)
				)
			)
		)
		(property "MPN" "GRM155R61A475MEAAD"
			(at 238.76 34.29 0)
			(effects
				(font
					(size 1.27 1.27)
					(thickness 0.15)
				)
				(justify left bottom)
				(hide yes)
			)
		)
		(property "Manufacturer" "Murata"
			(at 236.22 34.29 0)
			(effects
				(font
					(size 1.27 1.27)
					(thickness 0.15)
				)
				(justify left bottom)
				(hide yes)
			)
		)
		(property "License" "Apache-2.0"
			(at 233.68 34.29 0)
			(effects
				(font
					(size 1.27 1.27)
					(thickness 0.15)
				)
				(justify left bottom)
				(hide yes)
			)
		)
		(property "Author" "Antmicro"
			(at 231.14 34.29 0)
			(effects
				(font
					(size 1.27 1.27)
					(thickness 0.15)
				)
				(justify left bottom)
				(hide yes)
			)
		)
		(property "Val" "4u7"
			(at 254 53.3335 90)
			(effects
				(font
					(size 1.27 1.27)
					(thickness 0.15)
				)
				(justify right)
			)
		)
		(property "Voltage" ""
			(at 228.6 34.29 0)
			(effects
				(font
					(size 1.27 1.27)
				)
				(justify left bottom)
				(hide yes)
			)
		)
		(property "Dielectric" ""
			(at 226.06 34.29 0)
			(effects
				(font
					(size 1.27 1.27)
				)
				(justify left bottom)
				(hide yes)
			)
		)
		(pin "1"
		)
		(pin "2"
		)
		(instances
			(project ""
				(path ""
					(reference "C66")
					(unit 1)
				)
			)
		)
	)
	(symbol
		(lib_id "antmicropower:GND")
		(at 247.65 73.66 0)
		(unit 1)
		(exclude_from_sim no)
		(in_bom yes)
		(on_board yes)
		(dnp no)
		(property "Reference" "#PWR0189"
			(at 247.65 80.01 0)
			(effects
				(font
					(size 1.27 1.27)
				)
				(hide yes)
			)
		)
		(property "Value" "GND"
			(at 247.65 77.47 0)
			(effects
				(font
					(size 1.27 1.27)
				)
			)
		)
		(property "Footprint" ""
			(at 247.65 73.66 0)
			(effects
				(font
					(size 1.27 1.27)
				)
				(hide yes)
			)
		)
		(property "Datasheet" ""
			(at 247.65 73.66 0)
			(effects
				(font
					(size 1.27 1.27)
				)
				(hide yes)
			)
		)
		(property "Description" ""
			(at 247.65 73.66 0)
			(effects
				(font
					(size 1.27 1.27)
				)
			)
		)
		(pin "1"
		)
		(instances
			(project ""
				(path ""
					(reference "#PWR0189")
					(unit 1)
				)
			)
		)
	)
	(symbol
		(lib_id "antmicroCapacitors0402:C_4u7_0402")
		(at 274.32 40.64 270)
		(mirror x)
		(unit 1)
		(exclude_from_sim no)
		(in_bom yes)
		(on_board yes)
		(dnp no)
		(fields_autoplaced yes)
		(property "Reference" "C69"
			(at 271.78 36.8235 90)
			(effects
				(font
					(size 1.27 1.27)
					(thickness 0.15)
				)
				(justify right)
			)
		)
		(property "Value" "C_4u7_0402"
			(at 264.16 20.32 0)
			(effects
				(font
					(size 1.27 1.27)
					(thickness 0.15)
				)
				(justify left bottom)
				(hide yes)
			)
		)
		(property "Footprint" "antmicro-footprints:C_0402_1005Metric"
			(at 261.62 20.32 0)
			(effects
				(font
					(size 1.27 1.27)
					(thickness 0.15)
				)
				(justify left bottom)
				(hide yes)
			)
		)
		(property "Datasheet" "https://www.murata.com/products/productdetail?partno=GRM155R61A475MEAA%23"
			(at 259.08 20.32 0)
			(effects
				(font
					(size 1.27 1.27)
					(thickness 0.15)
				)
				(justify left bottom)
				(hide yes)
			)
		)
		(property "Description" ""
			(at 274.32 40.64 0)
			(effects
				(font
					(size 1.27 1.27)
				)
			)
		)
		(property "MPN" "GRM155R61A475MEAAD"
			(at 256.54 20.32 0)
			(effects
				(font
					(size 1.27 1.27)
					(thickness 0.15)
				)
				(justify left bottom)
				(hide yes)
			)
		)
		(property "Manufacturer" "Murata"
			(at 254 20.32 0)
			(effects
				(font
					(size 1.27 1.27)
					(thickness 0.15)
				)
				(justify left bottom)
				(hide yes)
			)
		)
		(property "License" "Apache-2.0"
			(at 251.46 20.32 0)
			(effects
				(font
					(size 1.27 1.27)
					(thickness 0.15)
				)
				(justify left bottom)
				(hide yes)
			)
		)
		(property "Author" "Antmicro"
			(at 248.92 20.32 0)
			(effects
				(font
					(size 1.27 1.27)
					(thickness 0.15)
				)
				(justify left bottom)
				(hide yes)
			)
		)
		(property "Val" "4u7"
			(at 271.78 39.3635 90)
			(effects
				(font
					(size 1.27 1.27)
					(thickness 0.15)
				)
				(justify right)
			)
		)
		(property "Voltage" ""
			(at 246.38 20.32 0)
			(effects
				(font
					(size 1.27 1.27)
				)
				(justify left bottom)
				(hide yes)
			)
		)
		(property "Dielectric" ""
			(at 243.84 20.32 0)
			(effects
				(font
					(size 1.27 1.27)
				)
				(justify left bottom)
				(hide yes)
			)
		)
		(pin "1"
		)
		(pin "2"
		)
		(instances
			(project ""
				(path ""
					(reference "C69")
					(unit 1)
				)
			)
		)
	)
	(symbol
		(lib_id "antmicropower:GND")
		(at 123.19 87.63 0)
		(unit 1)
		(exclude_from_sim no)
		(in_bom yes)
		(on_board yes)
		(dnp no)
		(property "Reference" "#PWR0171"
			(at 123.19 93.98 0)
			(effects
				(font
					(size 1.27 1.27)
				)
				(hide yes)
			)
		)
		(property "Value" "GND"
			(at 123.19 91.44 0)
			(effects
				(font
					(size 1.27 1.27)
				)
			)
		)
		(property "Footprint" ""
			(at 123.19 87.63 0)
			(effects
				(font
					(size 1.27 1.27)
				)
				(hide yes)
			)
		)
		(property "Datasheet" ""
			(at 123.19 87.63 0)
			(effects
				(font
					(size 1.27 1.27)
				)
				(hide yes)
			)
		)
		(property "Description" ""
			(at 123.19 87.63 0)
			(effects
				(font
					(size 1.27 1.27)
				)
			)
		)
		(pin "1"
		)
		(instances
			(project ""
				(path ""
					(reference "#PWR0171")
					(unit 1)
				)
			)
		)
	)
	(symbol
		(lib_id "antmicropower:GND")
		(at 256.54 73.66 0)
		(unit 1)
		(exclude_from_sim no)
		(in_bom yes)
		(on_board yes)
		(dnp no)
		(property "Reference" "#PWR0190"
			(at 256.54 80.01 0)
			(effects
				(font
					(size 1.27 1.27)
				)
				(hide yes)
			)
		)
		(property "Value" "GND"
			(at 256.54 77.47 0)
			(effects
				(font
					(size 1.27 1.27)
				)
			)
		)
		(property "Footprint" ""
			(at 256.54 73.66 0)
			(effects
				(font
					(size 1.27 1.27)
				)
				(hide yes)
			)
		)
		(property "Datasheet" ""
			(at 256.54 73.66 0)
			(effects
				(font
					(size 1.27 1.27)
				)
				(hide yes)
			)
		)
		(property "Description" ""
			(at 256.54 73.66 0)
			(effects
				(font
					(size 1.27 1.27)
				)
			)
		)
		(pin "1"
		)
		(instances
			(project ""
				(path ""
					(reference "#PWR0190")
					(unit 1)
				)
			)
		)
	)
	(symbol
		(lib_id "antmicropower:GND")
		(at 123.19 57.15 0)
		(unit 1)
		(exclude_from_sim no)
		(in_bom yes)
		(on_board yes)
		(dnp no)
		(property "Reference" "#PWR0203"
			(at 123.19 63.5 0)
			(effects
				(font
					(size 1.27 1.27)
				)
				(hide yes)
			)
		)
		(property "Value" "GND"
			(at 123.19 60.96 0)
			(effects
				(font
					(size 1.27 1.27)
				)
			)
		)
		(property "Footprint" ""
			(at 123.19 57.15 0)
			(effects
				(font
					(size 1.27 1.27)
				)
				(hide yes)
			)
		)
		(property "Datasheet" ""
			(at 123.19 57.15 0)
			(effects
				(font
					(size 1.27 1.27)
				)
				(hide yes)
			)
		)
		(property "Description" ""
			(at 123.19 57.15 0)
			(effects
				(font
					(size 1.27 1.27)
				)
			)
		)
		(pin "1"
		)
		(instances
			(project ""
				(path ""
					(reference "#PWR0203")
					(unit 1)
				)
			)
		)
	)
	(symbol
		(lib_id "antmicroCapacitors0402:C_4u7_0402")
		(at 238.76 54.61 270)
		(mirror x)
		(unit 1)
		(exclude_from_sim no)
		(in_bom yes)
		(on_board yes)
		(dnp no)
		(fields_autoplaced yes)
		(property "Reference" "C58"
			(at 236.22 50.7935 90)
			(effects
				(font
					(size 1.27 1.27)
					(thickness 0.15)
				)
				(justify right)
			)
		)
		(property "Value" "C_4u7_0402"
			(at 228.6 34.29 0)
			(effects
				(font
					(size 1.27 1.27)
					(thickness 0.15)
				)
				(justify left bottom)
				(hide yes)
			)
		)
		(property "Footprint" "antmicro-footprints:C_0402_1005Metric"
			(at 226.06 34.29 0)
			(effects
				(font
					(size 1.27 1.27)
					(thickness 0.15)
				)
				(justify left bottom)
				(hide yes)
			)
		)
		(property "Datasheet" "https://www.murata.com/products/productdetail?partno=GRM155R61A475MEAA%23"
			(at 223.52 34.29 0)
			(effects
				(font
					(size 1.27 1.27)
					(thickness 0.15)
				)
				(justify left bottom)
				(hide yes)
			)
		)
		(property "Description" ""
			(at 238.76 54.61 0)
			(effects
				(font
					(size 1.27 1.27)
				)
			)
		)
		(property "MPN" "GRM155R61A475MEAAD"
			(at 220.98 34.29 0)
			(effects
				(font
					(size 1.27 1.27)
					(thickness 0.15)
				)
				(justify left bottom)
				(hide yes)
			)
		)
		(property "Manufacturer" "Murata"
			(at 218.44 34.29 0)
			(effects
				(font
					(size 1.27 1.27)
					(thickness 0.15)
				)
				(justify left bottom)
				(hide yes)
			)
		)
		(property "License" "Apache-2.0"
			(at 215.9 34.29 0)
			(effects
				(font
					(size 1.27 1.27)
					(thickness 0.15)
				)
				(justify left bottom)
				(hide yes)
			)
		)
		(property "Author" "Antmicro"
			(at 213.36 34.29 0)
			(effects
				(font
					(size 1.27 1.27)
					(thickness 0.15)
				)
				(justify left bottom)
				(hide yes)
			)
		)
		(property "Val" "4u7"
			(at 236.22 53.3335 90)
			(effects
				(font
					(size 1.27 1.27)
					(thickness 0.15)
				)
				(justify right)
			)
		)
		(property "Voltage" ""
			(at 210.82 34.29 0)
			(effects
				(font
					(size 1.27 1.27)
				)
				(justify left bottom)
				(hide yes)
			)
		)
		(property "Dielectric" ""
			(at 208.28 34.29 0)
			(effects
				(font
					(size 1.27 1.27)
				)
				(justify left bottom)
				(hide yes)
			)
		)
		(pin "1"
		)
		(pin "2"
		)
		(instances
			(project ""
				(path ""
					(reference "C58")
					(unit 1)
				)
			)
		)
	)
	(symbol
		(lib_id "antmicropower:GND")
		(at 274.32 54.61 0)
		(mirror y)
		(unit 1)
		(exclude_from_sim no)
		(in_bom yes)
		(on_board yes)
		(dnp no)
		(property "Reference" "#PWR0201"
			(at 274.32 60.96 0)
			(effects
				(font
					(size 1.27 1.27)
				)
				(hide yes)
			)
		)
		(property "Value" "GND"
			(at 274.32 58.42 0)
			(effects
				(font
					(size 1.27 1.27)
				)
			)
		)
		(property "Footprint" ""
			(at 274.32 54.61 0)
			(effects
				(font
					(size 1.27 1.27)
				)
				(hide yes)
			)
		)
		(property "Datasheet" ""
			(at 274.32 54.61 0)
			(effects
				(font
					(size 1.27 1.27)
				)
				(hide yes)
			)
		)
		(property "Description" ""
			(at 274.32 54.61 0)
			(effects
				(font
					(size 1.27 1.27)
				)
			)
		)
		(pin "1"
		)
		(instances
			(project ""
				(path ""
					(reference "#PWR0201")
					(unit 1)
				)
			)
		)
	)
	(symbol
		(lib_id "antmicroCapacitors0402:C_4u7_0402")
		(at 123.19 87.63 90)
		(unit 1)
		(exclude_from_sim no)
		(in_bom yes)
		(on_board yes)
		(dnp no)
		(fields_autoplaced yes)
		(property "Reference" "C43"
			(at 125.73 83.8135 90)
			(effects
				(font
					(size 1.27 1.27)
					(thickness 0.15)
				)
				(justify right)
			)
		)
		(property "Value" "C_4u7_0402"
			(at 133.35 67.31 0)
			(effects
				(font
					(size 1.27 1.27)
					(thickness 0.15)
				)
				(justify left bottom)
				(hide yes)
			)
		)
		(property "Footprint" "antmicro-footprints:C_0402_1005Metric"
			(at 135.89 67.31 0)
			(effects
				(font
					(size 1.27 1.27)
					(thickness 0.15)
				)
				(justify left bottom)
				(hide yes)
			)
		)
		(property "Datasheet" "https://www.murata.com/products/productdetail?partno=GRM155R61A475MEAA%23"
			(at 138.43 67.31 0)
			(effects
				(font
					(size 1.27 1.27)
					(thickness 0.15)
				)
				(justify left bottom)
				(hide yes)
			)
		)
		(property "Description" ""
			(at 123.19 87.63 0)
			(effects
				(font
					(size 1.27 1.27)
				)
			)
		)
		(property "MPN" "GRM155R61A475MEAAD"
			(at 140.97 67.31 0)
			(effects
				(font
					(size 1.27 1.27)
					(thickness 0.15)
				)
				(justify left bottom)
				(hide yes)
			)
		)
		(property "Manufacturer" "Murata"
			(at 143.51 67.31 0)
			(effects
				(font
					(size 1.27 1.27)
					(thickness 0.15)
				)
				(justify left bottom)
				(hide yes)
			)
		)
		(property "License" "Apache-2.0"
			(at 146.05 67.31 0)
			(effects
				(font
					(size 1.27 1.27)
					(thickness 0.15)
				)
				(justify left bottom)
				(hide yes)
			)
		)
		(property "Author" "Antmicro"
			(at 148.59 67.31 0)
			(effects
				(font
					(size 1.27 1.27)
					(thickness 0.15)
				)
				(justify left bottom)
				(hide yes)
			)
		)
		(property "Val" "4u7"
			(at 125.73 86.3535 90)
			(effects
				(font
					(size 1.27 1.27)
					(thickness 0.15)
				)
				(justify right)
			)
		)
		(property "Voltage" ""
			(at 151.13 67.31 0)
			(effects
				(font
					(size 1.27 1.27)
				)
				(justify left bottom)
				(hide yes)
			)
		)
		(property "Dielectric" ""
			(at 153.67 67.31 0)
			(effects
				(font
					(size 1.27 1.27)
				)
				(justify left bottom)
				(hide yes)
			)
		)
		(pin "1"
		)
		(pin "2"
		)
		(instances
			(project ""
				(path ""
					(reference "C43")
					(unit 1)
				)
			)
		)
	)
	(symbol
		(lib_id "antmicropower:GND")
		(at 247.65 54.61 0)
		(mirror y)
		(unit 1)
		(exclude_from_sim no)
		(in_bom yes)
		(on_board yes)
		(dnp no)
		(property "Reference" "#PWR0193"
			(at 247.65 60.96 0)
			(effects
				(font
					(size 1.27 1.27)
				)
				(hide yes)
			)
		)
		(property "Value" "GND"
			(at 247.65 58.42 0)
			(effects
				(font
					(size 1.27 1.27)
				)
			)
		)
		(property "Footprint" ""
			(at 247.65 54.61 0)
			(effects
				(font
					(size 1.27 1.27)
				)
				(hide yes)
			)
		)
		(property "Datasheet" ""
			(at 247.65 54.61 0)
			(effects
				(font
					(size 1.27 1.27)
				)
				(hide yes)
			)
		)
		(property "Description" ""
			(at 247.65 54.61 0)
			(effects
				(font
					(size 1.27 1.27)
				)
			)
		)
		(pin "1"
		)
		(instances
			(project ""
				(path ""
					(reference "#PWR0193")
					(unit 1)
				)
			)
		)
	)
	(symbol
		(lib_id "antmicropower:GND")
		(at 283.21 40.64 0)
		(mirror y)
		(unit 1)
		(exclude_from_sim no)
		(in_bom yes)
		(on_board yes)
		(dnp no)
		(property "Reference" "#PWR0225"
			(at 283.21 46.99 0)
			(effects
				(font
					(size 1.27 1.27)
				)
				(hide yes)
			)
		)
		(property "Value" "GND"
			(at 283.21 44.45 0)
			(effects
				(font
					(size 1.27 1.27)
				)
			)
		)
		(property "Footprint" ""
			(at 283.21 40.64 0)
			(effects
				(font
					(size 1.27 1.27)
				)
				(hide yes)
			)
		)
		(property "Datasheet" ""
			(at 283.21 40.64 0)
			(effects
				(font
					(size 1.27 1.27)
				)
				(hide yes)
			)
		)
		(property "Description" ""
			(at 283.21 40.64 0)
			(effects
				(font
					(size 1.27 1.27)
				)
			)
		)
		(pin "1"
		)
		(instances
			(project ""
				(path ""
					(reference "#PWR0225")
					(unit 1)
				)
			)
		)
	)
	(symbol
		(lib_id "antmicroCapacitors0402:C_4u7_0402")
		(at 283.21 40.64 270)
		(mirror x)
		(unit 1)
		(exclude_from_sim no)
		(in_bom yes)
		(on_board yes)
		(dnp no)
		(fields_autoplaced yes)
		(property "Reference" "C76"
			(at 280.67 36.8235 90)
			(effects
				(font
					(size 1.27 1.27)
					(thickness 0.15)
				)
				(justify right)
			)
		)
		(property "Value" "C_4u7_0402"
			(at 273.05 20.32 0)
			(effects
				(font
					(size 1.27 1.27)
					(thickness 0.15)
				)
				(justify left bottom)
				(hide yes)
			)
		)
		(property "Footprint" "antmicro-footprints:C_0402_1005Metric"
			(at 270.51 20.32 0)
			(effects
				(font
					(size 1.27 1.27)
					(thickness 0.15)
				)
				(justify left bottom)
				(hide yes)
			)
		)
		(property "Datasheet" "https://www.murata.com/products/productdetail?partno=GRM155R61A475MEAA%23"
			(at 267.97 20.32 0)
			(effects
				(font
					(size 1.27 1.27)
					(thickness 0.15)
				)
				(justify left bottom)
				(hide yes)
			)
		)
		(property "Description" ""
			(at 283.21 40.64 0)
			(effects
				(font
					(size 1.27 1.27)
				)
			)
		)
		(property "MPN" "GRM155R61A475MEAAD"
			(at 265.43 20.32 0)
			(effects
				(font
					(size 1.27 1.27)
					(thickness 0.15)
				)
				(justify left bottom)
				(hide yes)
			)
		)
		(property "Manufacturer" "Murata"
			(at 262.89 20.32 0)
			(effects
				(font
					(size 1.27 1.27)
					(thickness 0.15)
				)
				(justify left bottom)
				(hide yes)
			)
		)
		(property "License" "Apache-2.0"
			(at 260.35 20.32 0)
			(effects
				(font
					(size 1.27 1.27)
					(thickness 0.15)
				)
				(justify left bottom)
				(hide yes)
			)
		)
		(property "Author" "Antmicro"
			(at 257.81 20.32 0)
			(effects
				(font
					(size 1.27 1.27)
					(thickness 0.15)
				)
				(justify left bottom)
				(hide yes)
			)
		)
		(property "Val" "4u7"
			(at 280.67 39.3635 90)
			(effects
				(font
					(size 1.27 1.27)
					(thickness 0.15)
				)
				(justify right)
			)
		)
		(property "Voltage" ""
			(at 255.27 20.32 0)
			(effects
				(font
					(size 1.27 1.27)
				)
				(justify left bottom)
				(hide yes)
			)
		)
		(property "Dielectric" ""
			(at 252.73 20.32 0)
			(effects
				(font
					(size 1.27 1.27)
				)
				(justify left bottom)
				(hide yes)
			)
		)
		(pin "1"
		)
		(pin "2"
		)
		(instances
			(project ""
				(path ""
					(reference "C76")
					(unit 1)
				)
			)
		)
	)
	(symbol
		(lib_id "antmicropower:GND")
		(at 229.87 40.64 0)
		(mirror y)
		(unit 1)
		(exclude_from_sim no)
		(in_bom yes)
		(on_board yes)
		(dnp no)
		(property "Reference" "#PWR0182"
			(at 229.87 46.99 0)
			(effects
				(font
					(size 1.27 1.27)
				)
				(hide yes)
			)
		)
		(property "Value" "GND"
			(at 229.87 44.45 0)
			(effects
				(font
					(size 1.27 1.27)
				)
			)
		)
		(property "Footprint" ""
			(at 229.87 40.64 0)
			(effects
				(font
					(size 1.27 1.27)
				)
				(hide yes)
			)
		)
		(property "Datasheet" ""
			(at 229.87 40.64 0)
			(effects
				(font
					(size 1.27 1.27)
				)
				(hide yes)
			)
		)
		(property "Description" ""
			(at 229.87 40.64 0)
			(effects
				(font
					(size 1.27 1.27)
				)
			)
		)
		(pin "1"
		)
		(instances
			(project ""
				(path ""
					(reference "#PWR0182")
					(unit 1)
				)
			)
		)
	)
	(symbol
		(lib_id "antmicropower:GND")
		(at 123.19 73.66 0)
		(unit 1)
		(exclude_from_sim no)
		(in_bom yes)
		(on_board yes)
		(dnp no)
		(property "Reference" "#PWR0178"
			(at 123.19 80.01 0)
			(effects
				(font
					(size 1.27 1.27)
				)
				(hide yes)
			)
		)
		(property "Value" "GND"
			(at 123.19 77.47 0)
			(effects
				(font
					(size 1.27 1.27)
				)
			)
		)
		(property "Footprint" ""
			(at 123.19 73.66 0)
			(effects
				(font
					(size 1.27 1.27)
				)
				(hide yes)
			)
		)
		(property "Datasheet" ""
			(at 123.19 73.66 0)
			(effects
				(font
					(size 1.27 1.27)
				)
				(hide yes)
			)
		)
		(property "Description" ""
			(at 123.19 73.66 0)
			(effects
				(font
					(size 1.27 1.27)
				)
			)
		)
		(pin "1"
		)
		(instances
			(project ""
				(path ""
					(reference "#PWR0178")
					(unit 1)
				)
			)
		)
	)
	(symbol
		(lib_id "antmicroCapacitors0402:C_4u7_0402")
		(at 247.65 40.64 270)
		(mirror x)
		(unit 1)
		(exclude_from_sim no)
		(in_bom yes)
		(on_board yes)
		(dnp no)
		(fields_autoplaced yes)
		(property "Reference" "C61"
			(at 245.11 36.8235 90)
			(effects
				(font
					(size 1.27 1.27)
					(thickness 0.15)
				)
				(justify right)
			)
		)
		(property "Value" "C_4u7_0402"
			(at 237.49 20.32 0)
			(effects
				(font
					(size 1.27 1.27)
					(thickness 0.15)
				)
				(justify left bottom)
				(hide yes)
			)
		)
		(property "Footprint" "antmicro-footprints:C_0402_1005Metric"
			(at 234.95 20.32 0)
			(effects
				(font
					(size 1.27 1.27)
					(thickness 0.15)
				)
				(justify left bottom)
				(hide yes)
			)
		)
		(property "Datasheet" "https://www.murata.com/products/productdetail?partno=GRM155R61A475MEAA%23"
			(at 232.41 20.32 0)
			(effects
				(font
					(size 1.27 1.27)
					(thickness 0.15)
				)
				(justify left bottom)
				(hide yes)
			)
		)
		(property "Description" ""
			(at 247.65 40.64 0)
			(effects
				(font
					(size 1.27 1.27)
				)
			)
		)
		(property "MPN" "GRM155R61A475MEAAD"
			(at 229.87 20.32 0)
			(effects
				(font
					(size 1.27 1.27)
					(thickness 0.15)
				)
				(justify left bottom)
				(hide yes)
			)
		)
		(property "Manufacturer" "Murata"
			(at 227.33 20.32 0)
			(effects
				(font
					(size 1.27 1.27)
					(thickness 0.15)
				)
				(justify left bottom)
				(hide yes)
			)
		)
		(property "License" "Apache-2.0"
			(at 224.79 20.32 0)
			(effects
				(font
					(size 1.27 1.27)
					(thickness 0.15)
				)
				(justify left bottom)
				(hide yes)
			)
		)
		(property "Author" "Antmicro"
			(at 222.25 20.32 0)
			(effects
				(font
					(size 1.27 1.27)
					(thickness 0.15)
				)
				(justify left bottom)
				(hide yes)
			)
		)
		(property "Val" "4u7"
			(at 245.11 39.3635 90)
			(effects
				(font
					(size 1.27 1.27)
					(thickness 0.15)
				)
				(justify right)
			)
		)
		(property "Voltage" ""
			(at 219.71 20.32 0)
			(effects
				(font
					(size 1.27 1.27)
				)
				(justify left bottom)
				(hide yes)
			)
		)
		(property "Dielectric" ""
			(at 217.17 20.32 0)
			(effects
				(font
					(size 1.27 1.27)
				)
				(justify left bottom)
				(hide yes)
			)
		)
		(pin "1"
		)
		(pin "2"
		)
		(instances
			(project ""
				(path ""
					(reference "C61")
					(unit 1)
				)
			)
		)
	)
	(symbol
		(lib_id "antmicropower:GND")
		(at 238.76 87.63 0)
		(unit 1)
		(exclude_from_sim no)
		(in_bom yes)
		(on_board yes)
		(dnp no)
		(property "Reference" "#PWR0188"
			(at 238.76 93.98 0)
			(effects
				(font
					(size 1.27 1.27)
				)
				(hide yes)
			)
		)
		(property "Value" "GND"
			(at 238.76 91.44 0)
			(effects
				(font
					(size 1.27 1.27)
				)
			)
		)
		(property "Footprint" ""
			(at 238.76 87.63 0)
			(effects
				(font
					(size 1.27 1.27)
				)
				(hide yes)
			)
		)
		(property "Datasheet" ""
			(at 238.76 87.63 0)
			(effects
				(font
					(size 1.27 1.27)
				)
				(hide yes)
			)
		)
		(property "Description" ""
			(at 238.76 87.63 0)
			(effects
				(font
					(size 1.27 1.27)
				)
			)
		)
		(pin "1"
		)
		(instances
			(project ""
				(path ""
					(reference "#PWR0188")
					(unit 1)
				)
			)
		)
	)
	(symbol
		(lib_id "antmicroCapacitors0402:C_4u7_0402")
		(at 274.32 54.61 270)
		(mirror x)
		(unit 1)
		(exclude_from_sim no)
		(in_bom yes)
		(on_board yes)
		(dnp no)
		(fields_autoplaced yes)
		(property "Reference" "C70"
			(at 271.78 50.7935 90)
			(effects
				(font
					(size 1.27 1.27)
					(thickness 0.15)
				)
				(justify right)
			)
		)
		(property "Value" "C_4u7_0402"
			(at 264.16 34.29 0)
			(effects
				(font
					(size 1.27 1.27)
					(thickness 0.15)
				)
				(justify left bottom)
				(hide yes)
			)
		)
		(property "Footprint" "antmicro-footprints:C_0402_1005Metric"
			(at 261.62 34.29 0)
			(effects
				(font
					(size 1.27 1.27)
					(thickness 0.15)
				)
				(justify left bottom)
				(hide yes)
			)
		)
		(property "Datasheet" "https://www.murata.com/products/productdetail?partno=GRM155R61A475MEAA%23"
			(at 259.08 34.29 0)
			(effects
				(font
					(size 1.27 1.27)
					(thickness 0.15)
				)
				(justify left bottom)
				(hide yes)
			)
		)
		(property "Description" ""
			(at 274.32 54.61 0)
			(effects
				(font
					(size 1.27 1.27)
				)
			)
		)
		(property "MPN" "GRM155R61A475MEAAD"
			(at 256.54 34.29 0)
			(effects
				(font
					(size 1.27 1.27)
					(thickness 0.15)
				)
				(justify left bottom)
				(hide yes)
			)
		)
		(property "Manufacturer" "Murata"
			(at 254 34.29 0)
			(effects
				(font
					(size 1.27 1.27)
					(thickness 0.15)
				)
				(justify left bottom)
				(hide yes)
			)
		)
		(property "License" "Apache-2.0"
			(at 251.46 34.29 0)
			(effects
				(font
					(size 1.27 1.27)
					(thickness 0.15)
				)
				(justify left bottom)
				(hide yes)
			)
		)
		(property "Author" "Antmicro"
			(at 248.92 34.29 0)
			(effects
				(font
					(size 1.27 1.27)
					(thickness 0.15)
				)
				(justify left bottom)
				(hide yes)
			)
		)
		(property "Val" "4u7"
			(at 271.78 53.3335 90)
			(effects
				(font
					(size 1.27 1.27)
					(thickness 0.15)
				)
				(justify right)
			)
		)
		(property "Voltage" ""
			(at 246.38 34.29 0)
			(effects
				(font
					(size 1.27 1.27)
				)
				(justify left bottom)
				(hide yes)
			)
		)
		(property "Dielectric" ""
			(at 243.84 34.29 0)
			(effects
				(font
					(size 1.27 1.27)
				)
				(justify left bottom)
				(hide yes)
			)
		)
		(pin "1"
		)
		(pin "2"
		)
		(instances
			(project ""
				(path ""
					(reference "C70")
					(unit 1)
				)
			)
		)
	)
	(symbol
		(lib_id "antmicropower:GND")
		(at 132.08 87.63 0)
		(unit 1)
		(exclude_from_sim no)
		(in_bom yes)
		(on_board yes)
		(dnp no)
		(property "Reference" "#PWR0186"
			(at 132.08 93.98 0)
			(effects
				(font
					(size 1.27 1.27)
				)
				(hide yes)
			)
		)
		(property "Value" "GND"
			(at 132.08 91.44 0)
			(effects
				(font
					(size 1.27 1.27)
				)
			)
		)
		(property "Footprint" ""
			(at 132.08 87.63 0)
			(effects
				(font
					(size 1.27 1.27)
				)
				(hide yes)
			)
		)
		(property "Datasheet" ""
			(at 132.08 87.63 0)
			(effects
				(font
					(size 1.27 1.27)
				)
				(hide yes)
			)
		)
		(property "Description" ""
			(at 132.08 87.63 0)
			(effects
				(font
					(size 1.27 1.27)
				)
			)
		)
		(pin "1"
		)
		(instances
			(project ""
				(path ""
					(reference "#PWR0186")
					(unit 1)
				)
			)
		)
	)
	(symbol
		(lib_id "antmicroCapacitors0402:C_4u7_0402")
		(at 149.86 57.15 90)
		(unit 1)
		(exclude_from_sim no)
		(in_bom yes)
		(on_board yes)
		(dnp no)
		(fields_autoplaced yes)
		(property "Reference" "C44"
			(at 152.4 53.3335 90)
			(effects
				(font
					(size 1.27 1.27)
					(thickness 0.15)
				)
				(justify right)
			)
		)
		(property "Value" "C_4u7_0402"
			(at 160.02 36.83 0)
			(effects
				(font
					(size 1.27 1.27)
					(thickness 0.15)
				)
				(justify left bottom)
				(hide yes)
			)
		)
		(property "Footprint" "antmicro-footprints:C_0402_1005Metric"
			(at 162.56 36.83 0)
			(effects
				(font
					(size 1.27 1.27)
					(thickness 0.15)
				)
				(justify left bottom)
				(hide yes)
			)
		)
		(property "Datasheet" "https://www.murata.com/products/productdetail?partno=GRM155R61A475MEAA%23"
			(at 165.1 36.83 0)
			(effects
				(font
					(size 1.27 1.27)
					(thickness 0.15)
				)
				(justify left bottom)
				(hide yes)
			)
		)
		(property "Description" ""
			(at 149.86 57.15 0)
			(effects
				(font
					(size 1.27 1.27)
				)
			)
		)
		(property "MPN" "GRM155R61A475MEAAD"
			(at 167.64 36.83 0)
			(effects
				(font
					(size 1.27 1.27)
					(thickness 0.15)
				)
				(justify left bottom)
				(hide yes)
			)
		)
		(property "Manufacturer" "Murata"
			(at 170.18 36.83 0)
			(effects
				(font
					(size 1.27 1.27)
					(thickness 0.15)
				)
				(justify left bottom)
				(hide yes)
			)
		)
		(property "License" "Apache-2.0"
			(at 172.72 36.83 0)
			(effects
				(font
					(size 1.27 1.27)
					(thickness 0.15)
				)
				(justify left bottom)
				(hide yes)
			)
		)
		(property "Author" "Antmicro"
			(at 175.26 36.83 0)
			(effects
				(font
					(size 1.27 1.27)
					(thickness 0.15)
				)
				(justify left bottom)
				(hide yes)
			)
		)
		(property "Val" "4u7"
			(at 152.4 55.8735 90)
			(effects
				(font
					(size 1.27 1.27)
					(thickness 0.15)
				)
				(justify right)
			)
		)
		(property "Voltage" ""
			(at 177.8 36.83 0)
			(effects
				(font
					(size 1.27 1.27)
				)
				(justify left bottom)
				(hide yes)
			)
		)
		(property "Dielectric" ""
			(at 180.34 36.83 0)
			(effects
				(font
					(size 1.27 1.27)
				)
				(justify left bottom)
				(hide yes)
			)
		)
		(pin "1"
		)
		(pin "2"
		)
		(instances
			(project ""
				(path ""
					(reference "C44")
					(unit 1)
				)
			)
		)
	)
)
